(lib_symbols
	(symbol "LED_G_0603_LG_L29K-G2J1-24-Z_1" (pin_numbers hide) (pin_names hide) (in_bom yes) (on_board yes)
      (property "Reference" "D" (at 20.32 -2.54 0)
        (effects (font (size 1.27 1.27) (thickness 0.15)) (justify left bottom))
      )
      (property "Value" "LED_G_0603_LG_L29K-G2J1-24-Z" (at 20.32 -7.62 0)
        (effects (font (size 1.27 1.27) (thickness 0.15)) (justify left bottom) hide)
      )
      (property "Footprint" "antmicro-footprints:LED_0603_1608Metric_G" (at 20.32 -10.16 0)
        (effects (font (size 1.27 1.27) (thickness 0.15)) (justify left bottom) hide)
      )
      (property "Datasheet" "https://look.ams-osram.com/m/19ee86b3ae0ee95b/original/LG-L29K.pdf" (at 20.32 -12.7 0)
        (effects (font (size 1.27 1.27) (thickness 0.15)) (justify left bottom) hide)
      )
      (property "MPN" "LG L29K-G2J1-24-Z" (at 20.32 -15.24 0)
        (effects (font (size 1.27 1.27) (thickness 0.15)) (justify left bottom) hide)
      )
      (property "Manufacturer" "OSRAM" (at 20.32 -17.78 0)
        (effects (font (size 1.27 1.27) (thickness 0.15)) (justify left bottom) hide)
      )
      (property "Color" "Green" (at 20.32 -5.08 0)
        (effects (font (size 1.27 1.27)) (justify left bottom))
      )
      (property "Author" "Antmicro" (at 20.32 -20.32 0)
        (effects (font (size 1.27 1.27) (thickness 0.15)) (justify left bottom) hide)
      )
      (property "License" "Apache-2.0" (at 20.32 -22.86 0)
        (effects (font (size 1.27 1.27) (thickness 0.15)) (justify left bottom) hide)
      )
      (property "ki_keywords" "SMT, DIODE, SEMICONDUCTOR, LED" (at 0 0 0)
        (effects (font (size 1.27 1.27)) hide)
      )
      (property "ki_description" "LED, Green, SMD, 0603, 20 mA, 1.7 V, 570 nm" (at 0 0 0)
        (effects (font (size 1.27 1.27)) hide)
      )
      (symbol "LED_G_0603_LG_L29K-G2J1-24-Z_1_0_1"
        (polyline
          (pts
            (xy 1.905 0)
            (xy 0.635 0)
          )
          (stroke (width 0) (type default))
          (fill (type none))
        )
        (polyline
          (pts
            (xy 4.445 0)
            (xy 3.175 0)
          )
          (stroke (width 0) (type default))
          (fill (type none))
        )
      )
      (symbol "LED_G_0603_LG_L29K-G2J1-24-Z_1_1_1"
        (polyline
          (pts
            (xy 1.778 1.016)
            (xy 1.778 -1.016)
          )
          (stroke (width 0.254) (type default))
          (fill (type none))
        )
        (polyline
          (pts
            (xy 3.302 1.016)
            (xy 3.302 -1.016)
            (xy 1.778 0)
            (xy 3.302 1.016)
          )
          (stroke (width 0.254) (type default))
          (fill (type outline))
        )
        (polyline
          (pts
            (xy 1.143 2.286)
            (xy 1.143 1.778)
            (xy 1.143 2.286)
            (xy 1.651 2.286)
            (xy 1.143 2.286)
            (xy 2.159 1.27)
          )
          (stroke (width 0.254) (type default))
          (fill (type none))
        )
        (polyline
          (pts
            (xy 2.159 2.54)
            (xy 2.159 2.032)
            (xy 2.159 2.54)
            (xy 2.667 2.54)
            (xy 2.159 2.54)
            (xy 3.048 1.651)
          )
          (stroke (width 0.254) (type default))
          (fill (type none))
        )
        (pin passive line (at 0 0 0) (length 0.635)
          (name "C" (effects (font (size 1.27 1.27))))
          (number "1" (effects (font (size 1.27 1.27))))
        )
        (pin passive line (at 5.08 0 180) (length 0.635)
          (name "A" (effects (font (size 1.27 1.27))))
          (number "2" (effects (font (size 1.27 1.27))))
        )
      )
    )
	(symbol "Oscillator_12MHz_ASFLMB_1" (in_bom yes) (on_board yes)
      (property "Reference" "Y" (at 25.4 -1.905 0)
        (effects (font (size 1.27 1.27) (thickness 0.15)) (justify left bottom))
      )
      (property "Value" "Oscillator_12MHz_ASFLMB" (at 25.4 -12.065 0)
        (effects (font (size 1.27 1.27) (thickness 0.15)) (justify left bottom) hide)
      )
      (property "Footprint" "antmicro-footprints:Oscillator_SMD_Abracon_ASFLMB_5x3.2x0.85mm" (at 25.4 -14.605 0)
        (effects (font (size 1.27 1.27) (thickness 0.15)) (justify left bottom) hide)
      )
      (property "Datasheet" "https://www.mouser.com/datasheet/2/3/ASFLMB-24525.pdf" (at 25.4 -17.145 0)
        (effects (font (size 1.27 1.27) (thickness 0.15)) (justify left bottom) hide)
      )
      (property "MPN" "ASFLMB-12.000MHZ-LC-T" (at 25.4 -4.445 0)
        (effects (font (size 1.27 1.27) (thickness 0.15)) (justify left bottom))
      )
      (property "Manufacturer" "Abracon" (at 25.4 -6.985 0)
        (effects (font (size 1.27 1.27) (thickness 0.15)) (justify left bottom) hide)
      )
      (property "Val" "12 MHz" (at 25.4 -9.525 0)
        (effects (font (size 1.27 1.27) (thickness 0.15)) (justify left bottom))
      )
      (property "Author" "Antmicro" (at 25.4 -19.685 0)
        (effects (font (size 1.27 1.27) (thickness 0.15)) (justify left bottom) hide)
      )
      (property "License" "Apache-2.0" (at 25.4 -22.225 0)
        (effects (font (size 1.27 1.27) (thickness 0.15)) (justify left bottom) hide)
      )
      (property "ki_keywords" "OSCILLATOR, MEMS" (at 0 0 0)
        (effects (font (size 1.27 1.27)) hide)
      )
      (property "ki_description" "MEMS Oscillator, 12 MHz, SMD, 5mm x 3.2mm, 50 ppm, 3.3 V, ASFLMB, LVCMOS" (at 0 0 0)
        (effects (font (size 1.27 1.27)) hide)
      )
      (symbol "Oscillator_12MHz_ASFLMB_1_1_1"
        (polyline
          (pts
            (xy 7.62 -1.27)
            (xy 8.255 -1.27)
            (xy 8.255 0)
            (xy 8.89 0)
            (xy 8.89 -1.27)
            (xy 9.525 -1.27)
            (xy 9.525 0)
            (xy 10.16 0)
            (xy 10.16 -1.27)
          )
          (stroke (width 0.254) (type default))
          (fill (type background))
        )
        (rectangle (start 2.54 2.54) (end 16.51 -7.62)
          (stroke (width 0.254) (type default))
          (fill (type background))
        )
        (pin input line (at 0 -2.54 0) (length 2.54)
          (name "EN" (effects (font (size 1.27 1.27))))
          (number "1" (effects (font (size 1.27 1.27))))
        )
        (pin power_in line (at 0 -5.08 0) (length 2.54)
          (name "GND" (effects (font (size 1.27 1.27))))
          (number "2" (effects (font (size 1.27 1.27))))
        )
        (pin output line (at 19.05 0 180) (length 2.54)
          (name "OUT" (effects (font (size 1.27 1.27))))
          (number "3" (effects (font (size 1.27 1.27))))
        )
        (pin power_in line (at 0 0 0) (length 2.54)
          (name "VDD" (effects (font (size 1.27 1.27))))
          (number "4" (effects (font (size 1.27 1.27))))
        )
      )
    )
	(symbol "Oscillator_24MHz_ASEMB_1" (in_bom yes) (on_board yes)
      (property "Reference" "Y" (at 17.78 -5.08 0)
        (effects (font (size 1.27 1.27) (thickness 0.15)) (justify left bottom))
      )
      (property "Value" "Oscillator_24MHz_ASEMB" (at 17.78 -15.24 0)
        (effects (font (size 1.27 1.27) (thickness 0.15)) (justify left bottom) hide)
      )
      (property "Footprint" "antmicro-footprints:Oscillator_SMD_Abracon_ASEMB_3.2x2.5mm" (at 17.78 -17.78 0)
        (effects (font (size 1.27 1.27) (thickness 0.15)) (justify left bottom) hide)
      )
      (property "Datasheet" "https://abracon.com/Oscillators/ASEMB.pdf" (at 17.78 -20.32 0)
        (effects (font (size 1.27 1.27) (thickness 0.15)) (justify left bottom) hide)
      )
      (property "MPN" "ASEMB-24.000MHZ-LC-T" (at 17.78 -7.62 0)
        (effects (font (size 1.27 1.27) (thickness 0.15)) (justify left bottom))
      )
      (property "Manufacturer" "Abracon" (at 17.78 -10.16 0)
        (effects (font (size 1.27 1.27) (thickness 0.15)) (justify left bottom) hide)
      )
      (property "Val" "24 MHz" (at 17.78 -12.7 0)
        (effects (font (size 1.27 1.27) (thickness 0.15)) (justify left bottom))
      )
      (property "Author" "Antmicro" (at 17.78 -22.86 0)
        (effects (font (size 1.27 1.27) (thickness 0.15)) (justify left bottom) hide)
      )
      (property "License" "Apache-2.0" (at 17.78 -25.4 0)
        (effects (font (size 1.27 1.27) (thickness 0.15)) (justify left bottom) hide)
      )
      (property "ki_keywords" "OSCILLATOR, MEMS" (at 0 0 0)
        (effects (font (size 1.27 1.27)) hide)
      )
      (property "ki_description" "MEMS Oscillator, Clock, Pure Silicon&trade;, 24 MHz, SMD, 3.2mm x 2.5mm, 50 ppm, 3.3 V, ASEMB, LVCMOS" (at 0 0 0)
        (effects (font (size 1.27 1.27)) hide)
      )
      (symbol "Oscillator_24MHz_ASEMB_1_1_1"
        (polyline
          (pts
            (xy 7.62 -1.27)
            (xy 8.255 -1.27)
            (xy 8.255 0)
            (xy 8.89 0)
            (xy 8.89 -1.27)
            (xy 9.525 -1.27)
            (xy 9.525 0)
            (xy 10.16 0)
            (xy 10.16 -1.27)
          )
          (stroke (width 0.254) (type default))
          (fill (type background))
        )
        (rectangle (start 2.54 2.54) (end 16.51 -7.62)
          (stroke (width 0.254) (type default))
          (fill (type background))
        )
        (pin input line (at 0 -2.54 0) (length 2.54)
          (name "EN" (effects (font (size 1.27 1.27))))
          (number "1" (effects (font (size 1.27 1.27))))
        )
        (pin power_in line (at 0 -5.08 0) (length 2.54)
          (name "GND" (effects (font (size 1.27 1.27))))
          (number "2" (effects (font (size 1.27 1.27))))
        )
        (pin output line (at 19.05 0 180) (length 2.54)
          (name "OUT" (effects (font (size 1.27 1.27))))
          (number "3" (effects (font (size 1.27 1.27))))
        )
        (pin power_in line (at 0 0 0) (length 2.54)
          (name "VDD" (effects (font (size 1.27 1.27))))
          (number "4" (effects (font (size 1.27 1.27))))
        )
      )
    )
	(symbol "PDS760_1" (pin_numbers hide) (pin_names hide) (in_bom yes) (on_board yes)
      (property "Reference" "D" (at 22.86 -5.08 0)
        (effects (font (size 1.27 1.27) (thickness 0.15)) (justify left bottom))
      )
      (property "Value" "PDS760" (at 22.86 -17.78 0)
        (effects (font (size 1.27 1.27) (thickness 0.15)) (justify left bottom) hide)
      )
      (property "Footprint" "antmicro-footprints:PowerDI5" (at 22.86 -10.16 0)
        (effects (font (size 1.27 1.27) (thickness 0.15)) (justify left bottom) hide)
      )
      (property "Datasheet" "https://www.diodes.com/assets/Datasheets/ds30470.pdf" (at 22.86 -12.7 0)
        (effects (font (size 1.27 1.27) (thickness 0.15)) (justify left bottom) hide)
      )
      (property "Manufacturer" "Diodes Incorporated" (at 22.86 -15.24 0)
        (effects (font (size 1.27 1.27) (thickness 0.15)) (justify left bottom) hide)
      )
      (property "MPN" "PDS760-13" (at 22.86 -7.62 0)
        (effects (font (size 1.27 1.27) (thickness 0.15)) (justify left bottom))
      )
      (property "Author" "Antmicro" (at 22.86 -20.32 0)
        (effects (font (size 1.27 1.27) (thickness 0.15)) (justify left bottom) hide)
      )
      (property "License" "Apache-2.0" (at 22.86 -22.86 0)
        (effects (font (size 1.27 1.27) (thickness 0.15)) (justify left bottom) hide)
      )
      (property "ki_keywords" "SMT, RECTIFIER, SEMICONDUCTOR, DIODE, SCHOTTKY" (at 0 0 0)
        (effects (font (size 1.27 1.27)) hide)
      )
      (property "ki_description" "Schottky Rectifier, POWERDI®, 60 V, 7 A, Single, PowerDI 5, 2 Pins, 620 mV" (at 0 0 0)
        (effects (font (size 1.27 1.27)) hide)
      )
      (symbol "PDS760_1_0_1"
        (polyline
          (pts
            (xy 1.905 0)
            (xy 0.635 0)
          )
          (stroke (width 0) (type default))
          (fill (type none))
        )
        (polyline
          (pts
            (xy 4.445 0)
            (xy 3.175 0)
          )
          (stroke (width 0) (type default))
          (fill (type none))
        )
      )
      (symbol "PDS760_1_1_1"
        (polyline
          (pts
            (xy 1.778 1.016)
            (xy 1.778 -1.016)
          )
          (stroke (width 0.254) (type default))
          (fill (type none))
        )
        (polyline
          (pts
            (xy 1.778 -1.016)
            (xy 2.159 -1.016)
            (xy 2.159 -0.762)
          )
          (stroke (width 0.254) (type default))
          (fill (type none))
        )
        (polyline
          (pts
            (xy 1.778 1.016)
            (xy 1.397 1.016)
            (xy 1.397 0.762)
          )
          (stroke (width 0.254) (type default))
          (fill (type none))
        )
        (polyline
          (pts
            (xy 3.302 1.016)
            (xy 3.302 -1.016)
            (xy 1.778 0)
            (xy 3.302 1.016)
          )
          (stroke (width 0.254) (type default))
          (fill (type outline))
        )
        (pin passive line (at 0 0 0) (length 0.635)
          (name "C" (effects (font (size 1.27 1.27))))
          (number "1" (effects (font (size 1.27 1.27))))
        )
        (pin passive line (at 5.08 0 180) (length 0.635)
          (name "A" (effects (font (size 1.27 1.27))))
          (number "2" (effects (font (size 1.27 1.27))))
        )
      )
    )
	(symbol "SW_B3U-1000P_SMD_1" (pin_names hide) (in_bom yes) (on_board yes)
      (property "Reference" "SW" (at 25.4 -2.54 0)
        (effects (font (size 1.27 1.27) (thickness 0.15)) (justify left bottom))
      )
      (property "Value" "SW_B3U-1000P_SMD" (at 25.4 -5.08 0)
        (effects (font (size 1.27 1.27) (thickness 0.15)) (justify left bottom) hide)
      )
      (property "Footprint" "antmicro-footprints:SW_B3U-1000P_SMD" (at 25.4 -7.62 0)
        (effects (font (size 1.27 1.27) (thickness 0.15)) (justify left bottom) hide)
      )
      (property "Datasheet" "https://omronfs.omron.com/en_US/ecb/products/pdf/en-b3u.pdf" (at 25.4 -10.16 0)
        (effects (font (size 1.27 1.27) (thickness 0.15)) (justify left bottom) hide)
      )
      (property "MPN" "B3U-1000P" (at 25.4 -12.7 0)
        (effects (font (size 1.27 1.27) (thickness 0.15)) (justify left bottom))
      )
      (property "Manufacturer" "Omron" (at 25.4 -15.24 0)
        (effects (font (size 1.27 1.27) (thickness 0.15)) (justify left bottom) hide)
      )
      (property "Author" "Antmicro" (at 25.4 -17.78 0)
        (effects (font (size 1.27 1.27) (thickness 0.15)) (justify left bottom) hide)
      )
      (property "License" "Apache-2.0" (at 25.4 -20.32 0)
        (effects (font (size 1.27 1.27) (thickness 0.15)) (justify left bottom) hide)
      )
      (property "ki_keywords" "VERTICAL, SMT, SWITCH, MECHANICAL, TACTILE" (at 0 0 0)
        (effects (font (size 1.27 1.27)) hide)
      )
      (property "ki_description" "Tactile Switch, B3U, Top Actuated, Surface Mount, Round Button, 153 gf, 50mA at 12VDC" (at 0 0 0)
        (effects (font (size 1.27 1.27)) hide)
      )
      (symbol "SW_B3U-1000P_SMD_1_1_1"
        (polyline
          (pts
            (xy 2.54 0)
            (xy 3.302 0)
          )
          (stroke (width 0.254) (type default))
          (fill (type none))
        )
        (polyline
          (pts
            (xy 3.302 1.27)
            (xy 6.858 1.27)
          )
          (stroke (width 0.254) (type default))
          (fill (type none))
        )
        (polyline
          (pts
            (xy 4.064 2.794)
            (xy 6.096 2.794)
          )
          (stroke (width 0.254) (type default))
          (fill (type none))
        )
        (polyline
          (pts
            (xy 5.08 1.27)
            (xy 5.08 2.794)
          )
          (stroke (width 0.254) (type default))
          (fill (type none))
        )
        (polyline
          (pts
            (xy 7.62 0)
            (xy 6.858 0)
          )
          (stroke (width 0.254) (type default))
          (fill (type none))
        )
        (circle (center 3.556 0) (radius 0.254)
          (stroke (width 0.254) (type default))
          (fill (type none))
        )
        (circle (center 6.604 0) (radius 0.254)
          (stroke (width 0.254) (type default))
          (fill (type none))
        )
        (pin passive line (at 0 0 0) (length 2.54)
          (name "1" (effects (font (size 1.27 1.27))))
          (number "1" (effects (font (size 1.27 1.27))))
        )
        (pin passive line (at 10.16 0 180) (length 2.54)
          (name "2" (effects (font (size 1.27 1.27))))
          (number "2" (effects (font (size 1.27 1.27))))
        )
      )
    )
	(symbol "antmicroB2BConnectors:Plug_Molex_SlimStack_2x25_529910508" (in_bom yes) (on_board yes)
      (property "Reference" "J" (at 25.4 0 0)
        (effects (font (size 1.27 1.27) (thickness 0.15)) (justify left bottom))
      )
      (property "Value" "Plug_Molex_SlimStack_2x25_529910508" (at 25.4 -5.08 0)
        (effects (font (size 1.27 1.27) (thickness 0.15)) (justify left bottom) hide)
      )
      (property "Footprint" "antmicro-footprints:Conn_Plug_Molex_SlimStack_2x25_529910508" (at 25.4 -7.62 0)
        (effects (font (size 1.27 1.27) (thickness 0.15)) (justify left bottom) hide)
      )
      (property "Datasheet" "https://www.molex.com/en-us/products/part-detail/529910508?display=pdf" (at 25.4 -10.16 0)
        (effects (font (size 1.27 1.27) (thickness 0.15)) (justify left bottom) hide)
      )
      (property "MPN" "529910508" (at 25.4 -2.54 0)
        (effects (font (size 1.27 1.27) (thickness 0.15)) (justify left bottom))
      )
      (property "Manufacturer" "Molex" (at 25.4 -12.7 0)
        (effects (font (size 1.27 1.27) (thickness 0.15)) (justify left bottom) hide)
      )
      (property "Author" "Antmicro" (at 25.4 -17.78 0)
        (effects (font (size 1.27 1.27) (thickness 0.15)) (justify left bottom) hide)
      )
      (property "License" "Apache-2.0" (at 25.4 -20.32 0)
        (effects (font (size 1.27 1.27) (thickness 0.15)) (justify left bottom) hide)
      )
      (property "Pitch " "0.5 mm" (at 25.4 -15.24 0)
        (effects (font (size 1.27 1.27)) (justify left bottom) hide)
      )
      (property "ki_keywords" "CONNECTOR, B2B, PLUG" (at 0 0 0)
        (effects (font (size 1.27 1.27)) hide)
      )
      (property "ki_description" "Mezzanine Connector, Receptacle, 0.5mm, 2Rows, 50Contacts, Surface Mount, Phosphor Bronze" (at 0 0 0)
        (effects (font (size 1.27 1.27)) hide)
      )
      (symbol "Plug_Molex_SlimStack_2x25_529910508_1_1"
        (rectangle (start 2.54 2.54) (end 8.89 -63.5)
          (stroke (width 0.254) (type default))
          (fill (type background))
        )
        (rectangle (start 3.81 1.27) (end 7.62 -62.23)
          (stroke (width 0.254) (type default))
          (fill (type background))
        )
        (pin passive line (at 0 0 0) (length 2.54)
          (name "~" (effects (font (size 1.27 1.27))))
          (number "1" (effects (font (size 1.27 1.27))))
        )
        (pin passive line (at 11.43 -10.16 180) (length 2.54)
          (name "~" (effects (font (size 1.27 1.27))))
          (number "10" (effects (font (size 1.27 1.27))))
        )
        (pin passive line (at 0 -12.7 0) (length 2.54)
          (name "~" (effects (font (size 1.27 1.27))))
          (number "11" (effects (font (size 1.27 1.27))))
        )
        (pin passive line (at 11.43 -12.7 180) (length 2.54)
          (name "~" (effects (font (size 1.27 1.27))))
          (number "12" (effects (font (size 1.27 1.27))))
        )
        (pin passive line (at 0 -15.24 0) (length 2.54)
          (name "~" (effects (font (size 1.27 1.27))))
          (number "13" (effects (font (size 1.27 1.27))))
        )
        (pin passive line (at 11.43 -15.24 180) (length 2.54)
          (name "~" (effects (font (size 1.27 1.27))))
          (number "14" (effects (font (size 1.27 1.27))))
        )
        (pin passive line (at 0 -17.78 0) (length 2.54)
          (name "~" (effects (font (size 1.27 1.27))))
          (number "15" (effects (font (size 1.27 1.27))))
        )
        (pin passive line (at 11.43 -17.78 180) (length 2.54)
          (name "~" (effects (font (size 1.27 1.27))))
          (number "16" (effects (font (size 1.27 1.27))))
        )
        (pin passive line (at 0 -20.32 0) (length 2.54)
          (name "~" (effects (font (size 1.27 1.27))))
          (number "17" (effects (font (size 1.27 1.27))))
        )
        (pin passive line (at 11.43 -20.32 180) (length 2.54)
          (name "~" (effects (font (size 1.27 1.27))))
          (number "18" (effects (font (size 1.27 1.27))))
        )
        (pin passive line (at 0 -22.86 0) (length 2.54)
          (name "~" (effects (font (size 1.27 1.27))))
          (number "19" (effects (font (size 1.27 1.27))))
        )
        (pin passive line (at 11.43 0 180) (length 2.54)
          (name "~" (effects (font (size 1.27 1.27))))
          (number "2" (effects (font (size 1.27 1.27))))
        )
        (pin passive line (at 11.43 -22.86 180) (length 2.54)
          (name "~" (effects (font (size 1.27 1.27))))
          (number "20" (effects (font (size 1.27 1.27))))
        )
        (pin passive line (at 0 -25.4 0) (length 2.54)
          (name "~" (effects (font (size 1.27 1.27))))
          (number "21" (effects (font (size 1.27 1.27))))
        )
        (pin passive line (at 11.43 -25.4 180) (length 2.54)
          (name "~" (effects (font (size 1.27 1.27))))
          (number "22" (effects (font (size 1.27 1.27))))
        )
        (pin passive line (at 0 -27.94 0) (length 2.54)
          (name "~" (effects (font (size 1.27 1.27))))
          (number "23" (effects (font (size 1.27 1.27))))
        )
        (pin passive line (at 11.43 -27.94 180) (length 2.54)
          (name "~" (effects (font (size 1.27 1.27))))
          (number "24" (effects (font (size 1.27 1.27))))
        )
        (pin passive line (at 0 -30.48 0) (length 2.54)
          (name "~" (effects (font (size 1.27 1.27))))
          (number "25" (effects (font (size 1.27 1.27))))
        )
        (pin passive line (at 11.43 -30.48 180) (length 2.54)
          (name "~" (effects (font (size 1.27 1.27))))
          (number "26" (effects (font (size 1.27 1.27))))
        )
        (pin passive line (at 0 -33.02 0) (length 2.54)
          (name "~" (effects (font (size 1.27 1.27))))
          (number "27" (effects (font (size 1.27 1.27))))
        )
        (pin passive line (at 11.43 -33.02 180) (length 2.54)
          (name "~" (effects (font (size 1.27 1.27))))
          (number "28" (effects (font (size 1.27 1.27))))
        )
        (pin passive line (at 0 -35.56 0) (length 2.54)
          (name "~" (effects (font (size 1.27 1.27))))
          (number "29" (effects (font (size 1.27 1.27))))
        )
        (pin passive line (at 0 -2.54 0) (length 2.54)
          (name "~" (effects (font (size 1.27 1.27))))
          (number "3" (effects (font (size 1.27 1.27))))
        )
        (pin passive line (at 11.43 -35.56 180) (length 2.54)
          (name "~" (effects (font (size 1.27 1.27))))
          (number "30" (effects (font (size 1.27 1.27))))
        )
        (pin passive line (at 0 -38.1 0) (length 2.54)
          (name "~" (effects (font (size 1.27 1.27))))
          (number "31" (effects (font (size 1.27 1.27))))
        )
        (pin passive line (at 11.43 -38.1 180) (length 2.54)
          (name "~" (effects (font (size 1.27 1.27))))
          (number "32" (effects (font (size 1.27 1.27))))
        )
        (pin passive line (at 0 -40.64 0) (length 2.54)
          (name "~" (effects (font (size 1.27 1.27))))
          (number "33" (effects (font (size 1.27 1.27))))
        )
        (pin passive line (at 11.43 -40.64 180) (length 2.54)
          (name "~" (effects (font (size 1.27 1.27))))
          (number "34" (effects (font (size 1.27 1.27))))
        )
        (pin passive line (at 0 -43.18 0) (length 2.54)
          (name "~" (effects (font (size 1.27 1.27))))
          (number "35" (effects (font (size 1.27 1.27))))
        )
        (pin passive line (at 11.43 -43.18 180) (length 2.54)
          (name "~" (effects (font (size 1.27 1.27))))
          (number "36" (effects (font (size 1.27 1.27))))
        )
        (pin passive line (at 0 -45.72 0) (length 2.54)
          (name "~" (effects (font (size 1.27 1.27))))
          (number "37" (effects (font (size 1.27 1.27))))
        )
        (pin passive line (at 11.43 -45.72 180) (length 2.54)
          (name "~" (effects (font (size 1.27 1.27))))
          (number "38" (effects (font (size 1.27 1.27))))
        )
        (pin passive line (at 0 -48.26 0) (length 2.54)
          (name "~" (effects (font (size 1.27 1.27))))
          (number "39" (effects (font (size 1.27 1.27))))
        )
        (pin passive line (at 11.43 -2.54 180) (length 2.54)
          (name "~" (effects (font (size 1.27 1.27))))
          (number "4" (effects (font (size 1.27 1.27))))
        )
        (pin passive line (at 11.43 -48.26 180) (length 2.54)
          (name "~" (effects (font (size 1.27 1.27))))
          (number "40" (effects (font (size 1.27 1.27))))
        )
        (pin passive line (at 0 -50.8 0) (length 2.54)
          (name "~" (effects (font (size 1.27 1.27))))
          (number "41" (effects (font (size 1.27 1.27))))
        )
        (pin passive line (at 11.43 -50.8 180) (length 2.54)
          (name "~" (effects (font (size 1.27 1.27))))
          (number "42" (effects (font (size 1.27 1.27))))
        )
        (pin passive line (at 0 -53.34 0) (length 2.54)
          (name "~" (effects (font (size 1.27 1.27))))
          (number "43" (effects (font (size 1.27 1.27))))
        )
        (pin passive line (at 11.43 -53.34 180) (length 2.54)
          (name "~" (effects (font (size 1.27 1.27))))
          (number "44" (effects (font (size 1.27 1.27))))
        )
        (pin passive line (at 0 -55.88 0) (length 2.54)
          (name "~" (effects (font (size 1.27 1.27))))
          (number "45" (effects (font (size 1.27 1.27))))
        )
        (pin passive line (at 11.43 -55.88 180) (length 2.54)
          (name "~" (effects (font (size 1.27 1.27))))
          (number "46" (effects (font (size 1.27 1.27))))
        )
        (pin passive line (at 0 -58.42 0) (length 2.54)
          (name "~" (effects (font (size 1.27 1.27))))
          (number "47" (effects (font (size 1.27 1.27))))
        )
        (pin passive line (at 11.43 -58.42 180) (length 2.54)
          (name "~" (effects (font (size 1.27 1.27))))
          (number "48" (effects (font (size 1.27 1.27))))
        )
        (pin passive line (at 0 -60.96 0) (length 2.54)
          (name "~" (effects (font (size 1.27 1.27))))
          (number "49" (effects (font (size 1.27 1.27))))
        )
        (pin passive line (at 0 -5.08 0) (length 2.54)
          (name "~" (effects (font (size 1.27 1.27))))
          (number "5" (effects (font (size 1.27 1.27))))
        )
        (pin passive line (at 11.43 -60.96 180) (length 2.54)
          (name "~" (effects (font (size 1.27 1.27))))
          (number "50" (effects (font (size 1.27 1.27))))
        )
        (pin passive line (at 11.43 -5.08 180) (length 2.54)
          (name "~" (effects (font (size 1.27 1.27))))
          (number "6" (effects (font (size 1.27 1.27))))
        )
        (pin passive line (at 0 -7.62 0) (length 2.54)
          (name "~" (effects (font (size 1.27 1.27))))
          (number "7" (effects (font (size 1.27 1.27))))
        )
        (pin passive line (at 11.43 -7.62 180) (length 2.54)
          (name "~" (effects (font (size 1.27 1.27))))
          (number "8" (effects (font (size 1.27 1.27))))
        )
        (pin passive line (at 0 -10.16 0) (length 2.54)
          (name "~" (effects (font (size 1.27 1.27))))
          (number "9" (effects (font (size 1.27 1.27))))
        )
      )
    )
	(symbol "antmicroCapacitors0402:C_100n_0402" (pin_numbers hide) (pin_names hide) (in_bom yes) (on_board yes)
      (property "Reference" "C" (at 20.32 -5.08 0)
        (effects (font (size 1.27 1.27) (thickness 0.15)) (justify left bottom))
      )
      (property "Value" "C_100n_0402" (at 20.32 -10.16 0)
        (effects (font (size 1.27 1.27) (thickness 0.15)) (justify left bottom) hide)
      )
      (property "Footprint" "antmicro-footprints:C_0402_1005Metric" (at 20.32 -12.7 0)
        (effects (font (size 1.27 1.27) (thickness 0.15)) (justify left bottom) hide)
      )
      (property "Datasheet" "https://www.murata.com/products/productdetail?partno=GRM155R61H104KE14%23" (at 20.32 -15.24 0)
        (effects (font (size 1.27 1.27) (thickness 0.15)) (justify left bottom) hide)
      )
      (property "MPN" "GRM155R61H104KE14D" (at 20.32 -17.78 0)
        (effects (font (size 1.27 1.27) (thickness 0.15)) (justify left bottom) hide)
      )
      (property "Manufacturer" "Murata" (at 20.32 -20.32 0)
        (effects (font (size 1.27 1.27) (thickness 0.15)) (justify left bottom) hide)
      )
      (property "License" "Apache-2.0" (at 20.32 -22.86 0)
        (effects (font (size 1.27 1.27) (thickness 0.15)) (justify left bottom) hide)
      )
      (property "Author" "Antmicro" (at 20.32 -25.4 0)
        (effects (font (size 1.27 1.27) (thickness 0.15)) (justify left bottom) hide)
      )
      (property "Val" "100n" (at 20.32 -7.62 0)
        (effects (font (size 1.27 1.27) (thickness 0.15)) (justify left bottom))
      )
      (property "Voltage" "50V" (at 20.32 -27.94 0)
        (effects (font (size 1.27 1.27)) (justify left bottom) hide)
      )
      (property "Dielectric" "X5R" (at 20.32 -30.48 0)
        (effects (font (size 1.27 1.27)) (justify left bottom) hide)
      )
      (property "ki_keywords" "0402, SMT, CAPACITOR, PASSIVE, CERAMIC, MLCC" (at 0 0 0)
        (effects (font (size 1.27 1.27)) hide)
      )
      (property "ki_description" "SMD Multilayer Ceramic Capacitor, 0.1 µF, 50 V, 0402 [1005 Metric], ± 10%, X5R, GRM Series" (at 0 0 0)
        (effects (font (size 1.27 1.27)) hide)
      )
      (symbol "C_100n_0402_0_1"
        (polyline
          (pts
            (xy 2.032 -1.524)
            (xy 2.032 1.524)
          )
          (stroke (width 0.3048) (type default))
          (fill (type none))
        )
        (polyline
          (pts
            (xy 3.048 -1.524)
            (xy 3.048 1.524)
          )
          (stroke (width 0.3302) (type default))
          (fill (type none))
        )
      )
      (symbol "C_100n_0402_1_1"
        (pin passive line (at 0 0 0) (length 2.032)
          (name "~" (effects (font (size 1.27 1.27))))
          (number "1" (effects (font (size 1.27 1.27))))
        )
        (pin passive line (at 5.08 0 180) (length 2.032)
          (name "~" (effects (font (size 1.27 1.27))))
          (number "2" (effects (font (size 1.27 1.27))))
        )
      )
    )
	(symbol "antmicroCapacitors0402:C_10n_0402" (pin_numbers hide) (pin_names hide) (in_bom yes) (on_board yes)
      (property "Reference" "C" (at 20.32 -5.08 0)
        (effects (font (size 1.27 1.27) (thickness 0.15)) (justify left bottom))
      )
      (property "Value" "C_10n_0402" (at 20.32 -10.16 0)
        (effects (font (size 1.27 1.27) (thickness 0.15)) (justify left bottom) hide)
      )
      (property "Footprint" "antmicro-footprints:C_0402_1005Metric" (at 20.32 -12.7 0)
        (effects (font (size 1.27 1.27) (thickness 0.15)) (justify left bottom) hide)
      )
      (property "Datasheet" "https://www.murata.com/products/productdetail?partno=GRM155R71H103KA88%23" (at 20.32 -15.24 0)
        (effects (font (size 1.27 1.27) (thickness 0.15)) (justify left bottom) hide)
      )
      (property "MPN" "GRM155R71H103KA88D" (at 20.32 -17.78 0)
        (effects (font (size 1.27 1.27) (thickness 0.15)) (justify left bottom) hide)
      )
      (property "Manufacturer" "Murata" (at 20.32 -20.32 0)
        (effects (font (size 1.27 1.27) (thickness 0.15)) (justify left bottom) hide)
      )
      (property "License" "Apache-2.0" (at 20.32 -22.86 0)
        (effects (font (size 1.27 1.27) (thickness 0.15)) (justify left bottom) hide)
      )
      (property "Author" "Antmicro" (at 20.32 -25.4 0)
        (effects (font (size 1.27 1.27) (thickness 0.15)) (justify left bottom) hide)
      )
      (property "Val" "10n" (at 20.32 -7.62 0)
        (effects (font (size 1.27 1.27) (thickness 0.15)) (justify left bottom))
      )
      (property "Voltage" "50V" (at 20.32 -27.94 0)
        (effects (font (size 1.27 1.27)) (justify left bottom) hide)
      )
      (property "Dielectric" "X7R" (at 20.32 -30.48 0)
        (effects (font (size 1.27 1.27)) (justify left bottom) hide)
      )
      (property "ki_keywords" "0402, SMT, CAPACITOR, PASSIVE" (at 0 0 0)
        (effects (font (size 1.27 1.27)) hide)
      )
      (property "ki_description" "SMD Multilayer Ceramic Capacitor, 10000 pF, 50 V, 0402 [1005 Metric], ± 10%, X7R, GRM Series" (at 0 0 0)
        (effects (font (size 1.27 1.27)) hide)
      )
      (symbol "C_10n_0402_0_1"
        (polyline
          (pts
            (xy 2.032 -1.524)
            (xy 2.032 1.524)
          )
          (stroke (width 0.3048) (type default))
          (fill (type none))
        )
        (polyline
          (pts
            (xy 3.048 -1.524)
            (xy 3.048 1.524)
          )
          (stroke (width 0.3302) (type default))
          (fill (type none))
        )
      )
      (symbol "C_10n_0402_1_1"
        (pin passive line (at 0 0 0) (length 2.032)
          (name "~" (effects (font (size 1.27 1.27))))
          (number "1" (effects (font (size 1.27 1.27))))
        )
        (pin passive line (at 5.08 0 180) (length 2.032)
          (name "~" (effects (font (size 1.27 1.27))))
          (number "2" (effects (font (size 1.27 1.27))))
        )
      )
    )
	(symbol "antmicroCapacitors0402:C_10u_0402" (pin_numbers hide) (pin_names hide) (in_bom yes) (on_board yes)
      (property "Reference" "C" (at 20.32 -5.08 0)
        (effects (font (size 1.27 1.27) (thickness 0.15)) (justify left bottom))
      )
      (property "Value" "C_10u_0402" (at 20.32 -10.16 0)
        (effects (font (size 1.27 1.27) (thickness 0.15)) (justify left bottom) hide)
      )
      (property "Footprint" "antmicro-footprints:C_0402_1005Metric" (at 20.32 -12.7 0)
        (effects (font (size 1.27 1.27) (thickness 0.15)) (justify left bottom) hide)
      )
      (property "Datasheet" "https://www.yageo.com/en/Chart/Download/pdf/CC0402MRX5R5BB106" (at 20.32 -15.24 0)
        (effects (font (size 1.27 1.27) (thickness 0.15)) (justify left bottom) hide)
      )
      (property "MPN" "CC0402MRX5R5BB106" (at 20.32 -17.78 0)
        (effects (font (size 1.27 1.27) (thickness 0.15)) (justify left bottom) hide)
      )
      (property "Manufacturer" "YAGEO" (at 20.32 -20.32 0)
        (effects (font (size 1.27 1.27) (thickness 0.15)) (justify left bottom) hide)
      )
      (property "License" "Apache-2.0" (at 20.32 -22.86 0)
        (effects (font (size 1.27 1.27) (thickness 0.15)) (justify left bottom) hide)
      )
      (property "Author" "Antmicro" (at 20.32 -25.4 0)
        (effects (font (size 1.27 1.27) (thickness 0.15)) (justify left bottom) hide)
      )
      (property "Val" "10u" (at 20.32 -7.62 0)
        (effects (font (size 1.27 1.27) (thickness 0.15)) (justify left bottom))
      )
      (property "Voltage" "" (at 20.32 -27.94 0)
        (effects (font (size 1.27 1.27)) (justify left bottom) hide)
      )
      (property "Dielectric" "" (at 20.32 -30.48 0)
        (effects (font (size 1.27 1.27)) (justify left bottom) hide)
      )
      (property "ki_keywords" "0402, SMT, CAPACITOR, PASSIVE, MLCC, CERAMIC" (at 0 0 0)
        (effects (font (size 1.27 1.27)) hide)
      )
      (property "ki_description" "SMD Multilayer Ceramic Capacitor, 10 µF, 6.3 V, 0402 [1005 Metric], ± 20%, X5R, CC Series" (at 0 0 0)
        (effects (font (size 1.27 1.27)) hide)
      )
      (symbol "C_10u_0402_0_1"
        (polyline
          (pts
            (xy 2.032 -1.524)
            (xy 2.032 1.524)
          )
          (stroke (width 0.3048) (type default))
          (fill (type none))
        )
        (polyline
          (pts
            (xy 3.048 -1.524)
            (xy 3.048 1.524)
          )
          (stroke (width 0.3302) (type default))
          (fill (type none))
        )
      )
      (symbol "C_10u_0402_1_1"
        (pin passive line (at 0 0 0) (length 2.032)
          (name "~" (effects (font (size 1.27 1.27))))
          (number "1" (effects (font (size 1.27 1.27))))
        )
        (pin passive line (at 5.08 0 180) (length 2.032)
          (name "~" (effects (font (size 1.27 1.27))))
          (number "2" (effects (font (size 1.27 1.27))))
        )
      )
    )
	(symbol "antmicroCapacitors0402:C_120p_100V_0402" (pin_numbers hide) (pin_names hide) (in_bom yes) (on_board yes)
      (property "Reference" "C" (at 20.32 -5.08 0)
        (effects (font (size 1.27 1.27) (thickness 0.15)) (justify left bottom))
      )
      (property "Value" "C_120p_100V_0402" (at 20.32 -10.16 0)
        (effects (font (size 1.27 1.27) (thickness 0.15)) (justify left bottom) hide)
      )
      (property "Footprint" "antmicro-footprints:C_0402_1005Metric" (at 20.32 -12.7 0)
        (effects (font (size 1.27 1.27) (thickness 0.15)) (justify left bottom) hide)
      )
      (property "Datasheet" "https://www.kemet.com/en/us/capacitors/product/C0402C121J5GACTU.html" (at 20.32 -15.24 0)
        (effects (font (size 1.27 1.27) (thickness 0.15)) (justify left bottom) hide)
      )
      (property "MPN" "C0402C121J5GACTU" (at 20.32 -17.78 0)
        (effects (font (size 1.27 1.27) (thickness 0.15)) (justify left bottom) hide)
      )
      (property "Manufacturer" "KEMET" (at 20.32 -20.32 0)
        (effects (font (size 1.27 1.27) (thickness 0.15)) (justify left bottom) hide)
      )
      (property "License" "Apache-2.0" (at 20.32 -22.86 0)
        (effects (font (size 1.27 1.27) (thickness 0.15)) (justify left bottom) hide)
      )
      (property "Author" "Antmicro" (at 20.32 -25.4 0)
        (effects (font (size 1.27 1.27) (thickness 0.15)) (justify left bottom) hide)
      )
      (property "Val" "120p" (at 20.32 -7.62 0)
        (effects (font (size 1.27 1.27) (thickness 0.15)) (justify left bottom))
      )
      (property "Voltage" "100V" (at 20.32 -27.94 0)
        (effects (font (size 1.27 1.27)) (justify left bottom) hide)
      )
      (property "Dielectric" "C0G" (at 20.32 -30.48 0)
        (effects (font (size 1.27 1.27)) (justify left bottom) hide)
      )
      (property "ki_keywords" "0402, SMT, CAPACITOR, PASSIVE, CERAMIC, MLCC" (at 0 0 0)
        (effects (font (size 1.27 1.27)) hide)
      )
      (property "ki_description" "120 pF ±2% 100V Ceramic Capacitor C0G, NP0 0402 (1005 Metric)" (at 0 0 0)
        (effects (font (size 1.27 1.27)) hide)
      )
      (symbol "C_120p_100V_0402_0_1"
        (polyline
          (pts
            (xy 2.032 -1.524)
            (xy 2.032 1.524)
          )
          (stroke (width 0.3048) (type default))
          (fill (type none))
        )
        (polyline
          (pts
            (xy 3.048 -1.524)
            (xy 3.048 1.524)
          )
          (stroke (width 0.3302) (type default))
          (fill (type none))
        )
      )
      (symbol "C_120p_100V_0402_1_1"
        (pin passive line (at 0 0 0) (length 2.032)
          (name "~" (effects (font (size 1.27 1.27))))
          (number "1" (effects (font (size 1.27 1.27))))
        )
        (pin passive line (at 5.08 0 180) (length 2.032)
          (name "~" (effects (font (size 1.27 1.27))))
          (number "2" (effects (font (size 1.27 1.27))))
        )
      )
    )
	(symbol "antmicroCapacitors0402:C_180p_0402" (pin_numbers hide) (pin_names hide) (in_bom yes) (on_board yes)
      (property "Reference" "C" (at 20.32 -5.08 0)
        (effects (font (size 1.27 1.27) (thickness 0.15)) (justify left bottom))
      )
      (property "Value" "C_180p_0402" (at 20.32 -10.16 0)
        (effects (font (size 1.27 1.27) (thickness 0.15)) (justify left bottom) hide)
      )
      (property "Footprint" "antmicro-footprints:C_0402_1005Metric" (at 20.32 -12.7 0)
        (effects (font (size 1.27 1.27) (thickness 0.15)) (justify left bottom) hide)
      )
      (property "Datasheet" "https://spicat.kyocera-avx.com/product/mlcc/chartview/04025A181JAT2A/" (at 20.32 -15.24 0)
        (effects (font (size 1.27 1.27) (thickness 0.15)) (justify left bottom) hide)
      )
      (property "MPN" "04025A181JAT2A" (at 20.32 -17.78 0)
        (effects (font (size 1.27 1.27) (thickness 0.15)) (justify left bottom) hide)
      )
      (property "Manufacturer" "AVX" (at 20.32 -20.32 0)
        (effects (font (size 1.27 1.27) (thickness 0.15)) (justify left bottom) hide)
      )
      (property "License" "Apache-2.0" (at 20.32 -22.86 0)
        (effects (font (size 1.27 1.27) (thickness 0.15)) (justify left bottom) hide)
      )
      (property "Author" "Antmicro" (at 20.32 -25.4 0)
        (effects (font (size 1.27 1.27) (thickness 0.15)) (justify left bottom) hide)
      )
      (property "Val" "180p" (at 20.32 -7.62 0)
        (effects (font (size 1.27 1.27) (thickness 0.15)) (justify left bottom))
      )
      (property "Voltage" "" (at 20.32 -27.94 0)
        (effects (font (size 1.27 1.27)) (justify left bottom) hide)
      )
      (property "Dielectric" "" (at 20.32 -30.48 0)
        (effects (font (size 1.27 1.27)) (justify left bottom) hide)
      )
      (property "ki_keywords" "0402, SMT, CAPACITOR, PASSIVE, CERAMIC, MLCC" (at 0 0 0)
        (effects (font (size 1.27 1.27)) hide)
      )
      (property "ki_description" "SMD Multilayer Ceramic Capacitor, 180 pF, 50 V, 0402 [1005 Metric], ± 5%, C0G / NP0, AVX 0402 MLCC" (at 0 0 0)
        (effects (font (size 1.27 1.27)) hide)
      )
      (symbol "C_180p_0402_0_1"
        (polyline
          (pts
            (xy 2.032 -1.524)
            (xy 2.032 1.524)
          )
          (stroke (width 0.3048) (type default))
          (fill (type none))
        )
        (polyline
          (pts
            (xy 3.048 -1.524)
            (xy 3.048 1.524)
          )
          (stroke (width 0.3302) (type default))
          (fill (type none))
        )
      )
      (symbol "C_180p_0402_1_1"
        (pin passive line (at 0 0 0) (length 2.032)
          (name "~" (effects (font (size 1.27 1.27))))
          (number "1" (effects (font (size 1.27 1.27))))
        )
        (pin passive line (at 5.08 0 180) (length 2.032)
          (name "~" (effects (font (size 1.27 1.27))))
          (number "2" (effects (font (size 1.27 1.27))))
        )
      )
    )
	(symbol "antmicroCapacitors0402:C_1n8_0402" (pin_numbers hide) (pin_names hide) (in_bom yes) (on_board yes)
      (property "Reference" "C" (at 20.32 -5.08 0)
        (effects (font (size 1.27 1.27) (thickness 0.15)) (justify left bottom))
      )
      (property "Value" "C_1n8_0402" (at 20.32 -10.16 0)
        (effects (font (size 1.27 1.27) (thickness 0.15)) (justify left bottom) hide)
      )
      (property "Footprint" "antmicro-footprints:C_0402_1005Metric" (at 20.32 -12.7 0)
        (effects (font (size 1.27 1.27) (thickness 0.15)) (justify left bottom) hide)
      )
      (property "Datasheet" "https://www.passivecomponent.com/wp-content/uploads/datasheet/WTC_MLCC_General_Purpose.pdf" (at 20.32 -15.24 0)
        (effects (font (size 1.27 1.27) (thickness 0.15)) (justify left bottom) hide)
      )
      (property "MPN" "0402B182K500CT" (at 20.32 -17.78 0)
        (effects (font (size 1.27 1.27) (thickness 0.15)) (justify left bottom) hide)
      )
      (property "Manufacturer" "Walsin" (at 20.32 -20.32 0)
        (effects (font (size 1.27 1.27) (thickness 0.15)) (justify left bottom) hide)
      )
      (property "License" "Apache-2.0" (at 20.32 -22.86 0)
        (effects (font (size 1.27 1.27) (thickness 0.15)) (justify left bottom) hide)
      )
      (property "Author" "Antmicro" (at 20.32 -25.4 0)
        (effects (font (size 1.27 1.27) (thickness 0.15)) (justify left bottom) hide)
      )
      (property "Val" "1n8" (at 20.32 -7.62 0)
        (effects (font (size 1.27 1.27) (thickness 0.15)) (justify left bottom))
      )
      (property "Voltage" "" (at 20.32 -27.94 0)
        (effects (font (size 1.27 1.27)) (justify left bottom) hide)
      )
      (property "Dielectric" "" (at 20.32 -30.48 0)
        (effects (font (size 1.27 1.27)) (justify left bottom) hide)
      )
      (property "ki_keywords" "0402, SMT, CAPACITOR, PASSIVE, MLCC" (at 0 0 0)
        (effects (font (size 1.27 1.27)) hide)
      )
      (property "ki_description" "SMD Multilayer Ceramic Capacitor, General Purpose, 1800 pF, 50 V, 0402 [1005 Metric], ± 10%, X7R" (at 0 0 0)
        (effects (font (size 1.27 1.27)) hide)
      )
      (symbol "C_1n8_0402_0_1"
        (polyline
          (pts
            (xy 2.032 -1.524)
            (xy 2.032 1.524)
          )
          (stroke (width 0.3048) (type default))
          (fill (type none))
        )
        (polyline
          (pts
            (xy 3.048 -1.524)
            (xy 3.048 1.524)
          )
          (stroke (width 0.3302) (type default))
          (fill (type none))
        )
      )
      (symbol "C_1n8_0402_1_1"
        (pin passive line (at 0 0 0) (length 2.032)
          (name "~" (effects (font (size 1.27 1.27))))
          (number "1" (effects (font (size 1.27 1.27))))
        )
        (pin passive line (at 5.08 0 180) (length 2.032)
          (name "~" (effects (font (size 1.27 1.27))))
          (number "2" (effects (font (size 1.27 1.27))))
        )
      )
    )
	(symbol "antmicroCapacitors0402:C_1n_0402" (pin_numbers hide) (pin_names hide) (in_bom yes) (on_board yes)
      (property "Reference" "C" (at 20.32 -5.08 0)
        (effects (font (size 1.27 1.27) (thickness 0.15)) (justify left bottom))
      )
      (property "Value" "C_1n_0402" (at 20.32 -10.16 0)
        (effects (font (size 1.27 1.27) (thickness 0.15)) (justify left bottom) hide)
      )
      (property "Footprint" "antmicro-footprints:C_0402_1005Metric" (at 20.32 -12.7 0)
        (effects (font (size 1.27 1.27) (thickness 0.15)) (justify left bottom) hide)
      )
      (property "Datasheet" "https://www.murata.com/products/productdetail?partno=GRM1555C1H102JA01%23" (at 20.32 -15.24 0)
        (effects (font (size 1.27 1.27) (thickness 0.15)) (justify left bottom) hide)
      )
      (property "MPN" "GRM1555C1H102JA01D" (at 20.32 -17.78 0)
        (effects (font (size 1.27 1.27) (thickness 0.15)) (justify left bottom) hide)
      )
      (property "Manufacturer" "Murata" (at 20.32 -20.32 0)
        (effects (font (size 1.27 1.27) (thickness 0.15)) (justify left bottom) hide)
      )
      (property "License" "Apache-2.0" (at 20.32 -22.86 0)
        (effects (font (size 1.27 1.27) (thickness 0.15)) (justify left bottom) hide)
      )
      (property "Author" "Antmicro" (at 20.32 -25.4 0)
        (effects (font (size 1.27 1.27) (thickness 0.15)) (justify left bottom) hide)
      )
      (property "Val" "1n" (at 20.32 -7.62 0)
        (effects (font (size 1.27 1.27) (thickness 0.15)) (justify left bottom))
      )
      (property "Voltage" "50V" (at 20.32 -27.94 0)
        (effects (font (size 1.27 1.27)) (justify left bottom) hide)
      )
      (property "Dielectric" "C0G" (at 20.32 -30.48 0)
        (effects (font (size 1.27 1.27)) (justify left bottom) hide)
      )
      (property "ki_keywords" "0402, SMT, CAPACITOR, PASSIVE, CERAMIC, MLCC" (at 0 0 0)
        (effects (font (size 1.27 1.27)) hide)
      )
      (property "ki_description" "SMD Multilayer Ceramic Capacitor, 1000 pF, 50 V, 0402 [1005 Metric], ± 5%, C0G / NP0, GRM Series" (at 0 0 0)
        (effects (font (size 1.27 1.27)) hide)
      )
      (symbol "C_1n_0402_0_1"
        (polyline
          (pts
            (xy 2.032 -1.524)
            (xy 2.032 1.524)
          )
          (stroke (width 0.3048) (type default))
          (fill (type none))
        )
        (polyline
          (pts
            (xy 3.048 -1.524)
            (xy 3.048 1.524)
          )
          (stroke (width 0.3302) (type default))
          (fill (type none))
        )
      )
      (symbol "C_1n_0402_1_1"
        (pin passive line (at 0 0 0) (length 2.032)
          (name "~" (effects (font (size 1.27 1.27))))
          (number "1" (effects (font (size 1.27 1.27))))
        )
        (pin passive line (at 5.08 0 180) (length 2.032)
          (name "~" (effects (font (size 1.27 1.27))))
          (number "2" (effects (font (size 1.27 1.27))))
        )
      )
    )
	(symbol "antmicroCapacitors0402:C_470n_0402" (pin_numbers hide) (pin_names hide) (in_bom yes) (on_board yes)
      (property "Reference" "C" (at 20.32 -5.08 0)
        (effects (font (size 1.27 1.27) (thickness 0.15)) (justify left bottom))
      )
      (property "Value" "C_470n_0402" (at 20.32 -10.16 0)
        (effects (font (size 1.27 1.27) (thickness 0.15)) (justify left bottom) hide)
      )
      (property "Footprint" "antmicro-footprints:C_0402_1005Metric" (at 20.32 -12.7 0)
        (effects (font (size 1.27 1.27) (thickness 0.15)) (justify left bottom) hide)
      )
      (property "Datasheet" "https://product.tdk.com/en/search/capacitor/ceramic/mlcc/info?part_no=C1005X5R1E474M050BB" (at 20.32 -15.24 0)
        (effects (font (size 1.27 1.27) (thickness 0.15)) (justify left bottom) hide)
      )
      (property "MPN" "C1005X5R1E474M050BB" (at 20.32 -17.78 0)
        (effects (font (size 1.27 1.27) (thickness 0.15)) (justify left bottom) hide)
      )
      (property "Manufacturer" "TDK" (at 20.32 -20.32 0)
        (effects (font (size 1.27 1.27) (thickness 0.15)) (justify left bottom) hide)
      )
      (property "License" "Apache-2.0" (at 20.32 -22.86 0)
        (effects (font (size 1.27 1.27) (thickness 0.15)) (justify left bottom) hide)
      )
      (property "Author" "Antmicro" (at 20.32 -25.4 0)
        (effects (font (size 1.27 1.27) (thickness 0.15)) (justify left bottom) hide)
      )
      (property "Val" "470n" (at 20.32 -7.62 0)
        (effects (font (size 1.27 1.27) (thickness 0.15)) (justify left bottom))
      )
      (property "Voltage" "" (at 20.32 -27.94 0)
        (effects (font (size 1.27 1.27)) (justify left bottom) hide)
      )
      (property "Dielectric" "" (at 20.32 -30.48 0)
        (effects (font (size 1.27 1.27)) (justify left bottom) hide)
      )
      (property "ki_keywords" "0402, SMT, CAPACITOR, PASSIVE, CERAMIC, MLCC" (at 0 0 0)
        (effects (font (size 1.27 1.27)) hide)
      )
      (property "ki_description" "SMD Multilayer Ceramic Capacitor, 0.47 µF, 25 V, 0402 [1005 Metric], ± 20%, X5R, C" (at 0 0 0)
        (effects (font (size 1.27 1.27)) hide)
      )
      (symbol "C_470n_0402_0_1"
        (polyline
          (pts
            (xy 2.032 -1.524)
            (xy 2.032 1.524)
          )
          (stroke (width 0.3048) (type default))
          (fill (type none))
        )
        (polyline
          (pts
            (xy 3.048 -1.524)
            (xy 3.048 1.524)
          )
          (stroke (width 0.3302) (type default))
          (fill (type none))
        )
      )
      (symbol "C_470n_0402_1_1"
        (pin passive line (at 0 0 0) (length 2.032)
          (name "~" (effects (font (size 1.27 1.27))))
          (number "1" (effects (font (size 1.27 1.27))))
        )
        (pin passive line (at 5.08 0 180) (length 2.032)
          (name "~" (effects (font (size 1.27 1.27))))
          (number "2" (effects (font (size 1.27 1.27))))
        )
      )
    )
	(symbol "antmicroCapacitors0402:C_47p_0402" (pin_numbers hide) (pin_names hide) (in_bom yes) (on_board yes)
      (property "Reference" "C" (at 20.32 -5.08 0)
        (effects (font (size 1.27 1.27) (thickness 0.15)) (justify left bottom))
      )
      (property "Value" "C_47p_0402" (at 20.32 -10.16 0)
        (effects (font (size 1.27 1.27) (thickness 0.15)) (justify left bottom) hide)
      )
      (property "Footprint" "antmicro-footprints:C_0402_1005Metric" (at 20.32 -12.7 0)
        (effects (font (size 1.27 1.27) (thickness 0.15)) (justify left bottom) hide)
      )
      (property "Datasheet" "https://www.kemet.com/en/us/capacitors/product/C0402C470J5GACTU.html" (at 20.32 -15.24 0)
        (effects (font (size 1.27 1.27) (thickness 0.15)) (justify left bottom) hide)
      )
      (property "MPN" "C0402C470J5GACTU" (at 20.32 -17.78 0)
        (effects (font (size 1.27 1.27) (thickness 0.15)) (justify left bottom) hide)
      )
      (property "Manufacturer" "KEMET" (at 20.32 -20.32 0)
        (effects (font (size 1.27 1.27) (thickness 0.15)) (justify left bottom) hide)
      )
      (property "License" "Apache-2.0" (at 20.32 -22.86 0)
        (effects (font (size 1.27 1.27) (thickness 0.15)) (justify left bottom) hide)
      )
      (property "Author" "Antmicro" (at 20.32 -25.4 0)
        (effects (font (size 1.27 1.27) (thickness 0.15)) (justify left bottom) hide)
      )
      (property "Val" "47p" (at 20.32 -7.62 0)
        (effects (font (size 1.27 1.27) (thickness 0.15)) (justify left bottom))
      )
      (property "Voltage" "" (at 20.32 -27.94 0)
        (effects (font (size 1.27 1.27)) (justify left bottom) hide)
      )
      (property "Dielectric" "C0G" (at 20.32 -30.48 0)
        (effects (font (size 1.27 1.27)) (justify left bottom) hide)
      )
      (property "ki_keywords" "0402, SMT, CAPACITOR, PASSIVE, CERAMIC, MLCC" (at 0 0 0)
        (effects (font (size 1.27 1.27)) hide)
      )
      (property "ki_description" "SMD Multilayer Ceramic Capacitor, 47 pF, 50 V, 0402 [1005 Metric], ± 5%, C0G / NP0, C Series KEMET" (at 0 0 0)
        (effects (font (size 1.27 1.27)) hide)
      )
      (symbol "C_47p_0402_0_1"
        (polyline
          (pts
            (xy 2.032 -1.524)
            (xy 2.032 1.524)
          )
          (stroke (width 0.3048) (type default))
          (fill (type none))
        )
        (polyline
          (pts
            (xy 3.048 -1.524)
            (xy 3.048 1.524)
          )
          (stroke (width 0.3302) (type default))
          (fill (type none))
        )
      )
      (symbol "C_47p_0402_1_1"
        (pin passive line (at 0 0 0) (length 2.032)
          (name "~" (effects (font (size 1.27 1.27))))
          (number "1" (effects (font (size 1.27 1.27))))
        )
        (pin passive line (at 5.08 0 180) (length 2.032)
          (name "~" (effects (font (size 1.27 1.27))))
          (number "2" (effects (font (size 1.27 1.27))))
        )
      )
    )
	(symbol "antmicroCapacitors0402:C_4n7_0402" (pin_numbers hide) (pin_names hide) (in_bom yes) (on_board yes)
      (property "Reference" "C" (at 20.32 -5.08 0)
        (effects (font (size 1.27 1.27) (thickness 0.15)) (justify left bottom))
      )
      (property "Value" "C_4n7_0402" (at 20.32 -10.16 0)
        (effects (font (size 1.27 1.27) (thickness 0.15)) (justify left bottom) hide)
      )
      (property "Footprint" "antmicro-footprints:C_0402_1005Metric" (at 20.32 -12.7 0)
        (effects (font (size 1.27 1.27) (thickness 0.15)) (justify left bottom) hide)
      )
      (property "Datasheet" "https://product.tdk.com/en/search/capacitor/ceramic/mlcc/info?part_no=CGA2B3X7S2A472K050BB" (at 20.32 -15.24 0)
        (effects (font (size 1.27 1.27) (thickness 0.15)) (justify left bottom) hide)
      )
      (property "MPN" "CGA2B3X7S2A472K050BB" (at 20.32 -17.78 0)
        (effects (font (size 1.27 1.27) (thickness 0.15)) (justify left bottom) hide)
      )
      (property "Manufacturer" "TDK" (at 20.32 -20.32 0)
        (effects (font (size 1.27 1.27) (thickness 0.15)) (justify left bottom) hide)
      )
      (property "License" "Apache-2.0" (at 20.32 -22.86 0)
        (effects (font (size 1.27 1.27) (thickness 0.15)) (justify left bottom) hide)
      )
      (property "Author" "Antmicro" (at 20.32 -25.4 0)
        (effects (font (size 1.27 1.27) (thickness 0.15)) (justify left bottom) hide)
      )
      (property "Val" "4n7" (at 20.32 -7.62 0)
        (effects (font (size 1.27 1.27) (thickness 0.15)) (justify left bottom))
      )
      (property "Voltage" "" (at 20.32 -27.94 0)
        (effects (font (size 1.27 1.27)) (justify left bottom) hide)
      )
      (property "Dielectric" "" (at 20.32 -30.48 0)
        (effects (font (size 1.27 1.27)) (justify left bottom) hide)
      )
      (property "ki_keywords" "0402, SMT, CAPACITOR, PASSIVE, CERAMIC, MLCC" (at 0 0 0)
        (effects (font (size 1.27 1.27)) hide)
      )
      (property "ki_description" "SMD Multilayer Ceramic Capacitor, 4700 pF, 100 V, 0402 [1005 Metric], ± 10%, X7S, CGA" (at 0 0 0)
        (effects (font (size 1.27 1.27)) hide)
      )
      (symbol "C_4n7_0402_0_1"
        (polyline
          (pts
            (xy 2.032 -1.524)
            (xy 2.032 1.524)
          )
          (stroke (width 0.3048) (type default))
          (fill (type none))
        )
        (polyline
          (pts
            (xy 3.048 -1.524)
            (xy 3.048 1.524)
          )
          (stroke (width 0.3302) (type default))
          (fill (type none))
        )
      )
      (symbol "C_4n7_0402_1_1"
        (pin passive line (at 0 0 0) (length 2.032)
          (name "~" (effects (font (size 1.27 1.27))))
          (number "1" (effects (font (size 1.27 1.27))))
        )
        (pin passive line (at 5.08 0 180) (length 2.032)
          (name "~" (effects (font (size 1.27 1.27))))
          (number "2" (effects (font (size 1.27 1.27))))
        )
      )
    )
	(symbol "antmicroCapacitors0402:C_4u7_0402" (pin_numbers hide) (pin_names hide) (in_bom yes) (on_board yes)
      (property "Reference" "C" (at 20.32 -5.08 0)
        (effects (font (size 1.27 1.27) (thickness 0.15)) (justify left bottom))
      )
      (property "Value" "C_4u7_0402" (at 20.32 -10.16 0)
        (effects (font (size 1.27 1.27) (thickness 0.15)) (justify left bottom) hide)
      )
      (property "Footprint" "antmicro-footprints:C_0402_1005Metric" (at 20.32 -12.7 0)
        (effects (font (size 1.27 1.27) (thickness 0.15)) (justify left bottom) hide)
      )
      (property "Datasheet" "https://www.murata.com/products/productdetail?partno=GRM155R61A475MEAA%23" (at 20.32 -15.24 0)
        (effects (font (size 1.27 1.27) (thickness 0.15)) (justify left bottom) hide)
      )
      (property "MPN" "GRM155R61A475MEAAD" (at 20.32 -17.78 0)
        (effects (font (size 1.27 1.27) (thickness 0.15)) (justify left bottom) hide)
      )
      (property "Manufacturer" "Murata" (at 20.32 -20.32 0)
        (effects (font (size 1.27 1.27) (thickness 0.15)) (justify left bottom) hide)
      )
      (property "License" "Apache-2.0" (at 20.32 -22.86 0)
        (effects (font (size 1.27 1.27) (thickness 0.15)) (justify left bottom) hide)
      )
      (property "Author" "Antmicro" (at 20.32 -25.4 0)
        (effects (font (size 1.27 1.27) (thickness 0.15)) (justify left bottom) hide)
      )
      (property "Val" "4u7" (at 20.32 -7.62 0)
        (effects (font (size 1.27 1.27) (thickness 0.15)) (justify left bottom))
      )
      (property "Voltage" "" (at 20.32 -27.94 0)
        (effects (font (size 1.27 1.27)) (justify left bottom) hide)
      )
      (property "Dielectric" "" (at 20.32 -30.48 0)
        (effects (font (size 1.27 1.27)) (justify left bottom) hide)
      )
      (property "ki_keywords" "0402, SMT, CAPACITOR, PASSIVE" (at 0 0 0)
        (effects (font (size 1.27 1.27)) hide)
      )
      (property "ki_description" "SMD Multilayer Ceramic Capacitor, 4.7 µF, 10 V, 0402 [1005 Metric], ± 20%, X5R, GRM Series" (at 0 0 0)
        (effects (font (size 1.27 1.27)) hide)
      )
      (symbol "C_4u7_0402_0_1"
        (polyline
          (pts
            (xy 2.032 -1.524)
            (xy 2.032 1.524)
          )
          (stroke (width 0.3048) (type default))
          (fill (type none))
        )
        (polyline
          (pts
            (xy 3.048 -1.524)
            (xy 3.048 1.524)
          )
          (stroke (width 0.3302) (type default))
          (fill (type none))
        )
      )
      (symbol "C_4u7_0402_1_1"
        (pin passive line (at 0 0 0) (length 2.032)
          (name "~" (effects (font (size 1.27 1.27))))
          (number "1" (effects (font (size 1.27 1.27))))
        )
        (pin passive line (at 5.08 0 180) (length 2.032)
          (name "~" (effects (font (size 1.27 1.27))))
          (number "2" (effects (font (size 1.27 1.27))))
        )
      )
    )
	(symbol "antmicroCapacitors0402:C_750p_0402" (pin_numbers hide) (pin_names hide) (in_bom yes) (on_board yes)
      (property "Reference" "C" (at 20.32 -5.08 0)
        (effects (font (size 1.27 1.27) (thickness 0.15)) (justify left bottom))
      )
      (property "Value" "C_750p_0402" (at 20.32 -10.16 0)
        (effects (font (size 1.27 1.27) (thickness 0.15)) (justify left bottom) hide)
      )
      (property "Footprint" "antmicro-footprints:C_0402_1005Metric" (at 20.32 -12.7 0)
        (effects (font (size 1.27 1.27) (thickness 0.15)) (justify left bottom) hide)
      )
      (property "Datasheet" "https://www.kemet.com/en/us/capacitors/product/C0402C751J5GACTU.html" (at 20.32 -15.24 0)
        (effects (font (size 1.27 1.27) (thickness 0.15)) (justify left bottom) hide)
      )
      (property "MPN" "C0402C751J5GACTU" (at 20.32 -17.78 0)
        (effects (font (size 1.27 1.27) (thickness 0.15)) (justify left bottom) hide)
      )
      (property "Manufacturer" "KEMET" (at 20.32 -20.32 0)
        (effects (font (size 1.27 1.27) (thickness 0.15)) (justify left bottom) hide)
      )
      (property "License" "Apache-2.0" (at 20.32 -22.86 0)
        (effects (font (size 1.27 1.27) (thickness 0.15)) (justify left bottom) hide)
      )
      (property "Author" "Antmicro" (at 20.32 -25.4 0)
        (effects (font (size 1.27 1.27) (thickness 0.15)) (justify left bottom) hide)
      )
      (property "Val" "750p" (at 20.32 -7.62 0)
        (effects (font (size 1.27 1.27) (thickness 0.15)) (justify left bottom))
      )
      (property "Voltage" "" (at 20.32 -27.94 0)
        (effects (font (size 1.27 1.27)) (justify left bottom) hide)
      )
      (property "Dielectric" "" (at 20.32 -30.48 0)
        (effects (font (size 1.27 1.27)) (justify left bottom) hide)
      )
      (property "ki_keywords" "0402, SMT, CAPACITOR, PASSIVE, CERAMIC, MLCC" (at 0 0 0)
        (effects (font (size 1.27 1.27)) hide)
      )
      (property "ki_description" "SMD Multilayer Ceramic Capacitor, 750 pF, 50 V, 0402 [1005 Metric], ± 5%, C0G / NP0" (at 0 0 0)
        (effects (font (size 1.27 1.27)) hide)
      )
      (symbol "C_750p_0402_0_1"
        (polyline
          (pts
            (xy 2.032 -1.524)
            (xy 2.032 1.524)
          )
          (stroke (width 0.3048) (type default))
          (fill (type none))
        )
        (polyline
          (pts
            (xy 3.048 -1.524)
            (xy 3.048 1.524)
          )
          (stroke (width 0.3302) (type default))
          (fill (type none))
        )
      )
      (symbol "C_750p_0402_1_1"
        (pin passive line (at 0 0 0) (length 2.032)
          (name "~" (effects (font (size 1.27 1.27))))
          (number "1" (effects (font (size 1.27 1.27))))
        )
        (pin passive line (at 5.08 0 180) (length 2.032)
          (name "~" (effects (font (size 1.27 1.27))))
          (number "2" (effects (font (size 1.27 1.27))))
        )
      )
    )
	(symbol "antmicroCapacitors0603:C_10u_25V_0603" (pin_numbers hide) (pin_names hide) (in_bom yes) (on_board yes)
      (property "Reference" "C" (at 20.32 -5.08 0)
        (effects (font (size 1.27 1.27) (thickness 0.15)) (justify left bottom))
      )
      (property "Value" "C_10u_25V_0603" (at 20.32 -10.16 0)
        (effects (font (size 1.27 1.27) (thickness 0.15)) (justify left bottom) hide)
      )
      (property "Footprint" "antmicro-footprints:C_0603_1608Metric" (at 20.32 -12.7 0)
        (effects (font (size 1.27 1.27) (thickness 0.15)) (justify left bottom) hide)
      )
      (property "Datasheet" "https://product.tdk.com/en/search/capacitor/ceramic/mlcc/info?part_no=C1608X5R1E106M080AC" (at 20.32 -15.24 0)
        (effects (font (size 1.27 1.27) (thickness 0.15)) (justify left bottom) hide)
      )
      (property "MPN" "C1608X5R1E106M080AC" (at 20.32 -17.78 0)
        (effects (font (size 1.27 1.27) (thickness 0.15)) (justify left bottom) hide)
      )
      (property "Manufacturer" "TDK" (at 20.32 -20.32 0)
        (effects (font (size 1.27 1.27) (thickness 0.15)) (justify left bottom) hide)
      )
      (property "License" "Apache-2.0" (at 20.32 -22.86 0)
        (effects (font (size 1.27 1.27) (thickness 0.15)) (justify left bottom) hide)
      )
      (property "Author" "Antmicro" (at 20.32 -25.4 0)
        (effects (font (size 1.27 1.27) (thickness 0.15)) (justify left bottom) hide)
      )
      (property "Val" "10u" (at 20.32 -7.62 0)
        (effects (font (size 1.27 1.27) (thickness 0.15)) (justify left bottom))
      )
      (property "Voltage" "25V" (at 20.32 -27.94 0)
        (effects (font (size 1.27 1.27)) (justify left bottom) hide)
      )
      (property "Dielectric" "" (at 20.32 -30.48 0)
        (effects (font (size 1.27 1.27)) (justify left bottom) hide)
      )
      (property "ki_keywords" "0603, SMT, CAPACITOR, PASSIVE, CERAMIC, MLCC" (at 0 0 0)
        (effects (font (size 1.27 1.27)) hide)
      )
      (property "ki_description" "SMD Multilayer Ceramic Capacitor, 10 µF, 25 V, 0603 [1608 Metric], ± 20%, X5R, C" (at 0 0 0)
        (effects (font (size 1.27 1.27)) hide)
      )
      (symbol "C_10u_25V_0603_0_1"
        (polyline
          (pts
            (xy 2.032 -1.524)
            (xy 2.032 1.524)
          )
          (stroke (width 0.3048) (type default))
          (fill (type none))
        )
        (polyline
          (pts
            (xy 3.048 -1.524)
            (xy 3.048 1.524)
          )
          (stroke (width 0.3302) (type default))
          (fill (type none))
        )
      )
      (symbol "C_10u_25V_0603_1_1"
        (pin passive line (at 0 0 0) (length 2.032)
          (name "~" (effects (font (size 1.27 1.27))))
          (number "1" (effects (font (size 1.27 1.27))))
        )
        (pin passive line (at 5.08 0 180) (length 2.032)
          (name "~" (effects (font (size 1.27 1.27))))
          (number "2" (effects (font (size 1.27 1.27))))
        )
      )
    )
	(symbol "antmicroCapacitors0603:C_22u_0603" (pin_numbers hide) (pin_names hide) (in_bom yes) (on_board yes)
      (property "Reference" "C" (at 20.32 -5.08 0)
        (effects (font (size 1.27 1.27) (thickness 0.15)) (justify left bottom))
      )
      (property "Value" "C_22u_0603" (at 20.32 -10.16 0)
        (effects (font (size 1.27 1.27) (thickness 0.15)) (justify left bottom) hide)
      )
      (property "Footprint" "antmicro-footprints:C_0603_1608Metric" (at 20.32 -12.7 0)
        (effects (font (size 1.27 1.27) (thickness 0.15)) (justify left bottom) hide)
      )
      (property "Datasheet" "https://www.murata.com/products/productdetail?partno=GRM188R60J226MEA0%23" (at 20.32 -15.24 0)
        (effects (font (size 1.27 1.27) (thickness 0.15)) (justify left bottom) hide)
      )
      (property "MPN" "GRM188R60J226MEA0D" (at 20.32 -17.78 0)
        (effects (font (size 1.27 1.27) (thickness 0.15)) (justify left bottom) hide)
      )
      (property "Manufacturer" "Murata" (at 20.32 -20.32 0)
        (effects (font (size 1.27 1.27) (thickness 0.15)) (justify left bottom) hide)
      )
      (property "License" "Apache-2.0" (at 20.32 -22.86 0)
        (effects (font (size 1.27 1.27) (thickness 0.15)) (justify left bottom) hide)
      )
      (property "Author" "Antmicro" (at 20.32 -25.4 0)
        (effects (font (size 1.27 1.27) (thickness 0.15)) (justify left bottom) hide)
      )
      (property "Val" "22u" (at 20.32 -7.62 0)
        (effects (font (size 1.27 1.27) (thickness 0.15)) (justify left bottom))
      )
      (property "Voltage" "" (at 20.32 -27.94 0)
        (effects (font (size 1.27 1.27)) (justify left bottom) hide)
      )
      (property "Dielectric" "" (at 20.32 -30.48 0)
        (effects (font (size 1.27 1.27)) (justify left bottom) hide)
      )
      (property "ki_keywords" "0603, SMT, CAPACITOR, PASSIVE, CERAMIC, MLCC" (at 0 0 0)
        (effects (font (size 1.27 1.27)) hide)
      )
      (property "ki_description" "SMD Multilayer Ceramic Capacitor, 22 µF, 6.3 V, 0603 [1608 Metric], ± 20%, X5R, GRM Series" (at 0 0 0)
        (effects (font (size 1.27 1.27)) hide)
      )
      (symbol "C_22u_0603_0_1"
        (polyline
          (pts
            (xy 2.032 -1.524)
            (xy 2.032 1.524)
          )
          (stroke (width 0.3048) (type default))
          (fill (type none))
        )
        (polyline
          (pts
            (xy 3.048 -1.524)
            (xy 3.048 1.524)
          )
          (stroke (width 0.3302) (type default))
          (fill (type none))
        )
      )
      (symbol "C_22u_0603_1_1"
        (pin passive line (at 0 0 0) (length 2.032)
          (name "~" (effects (font (size 1.27 1.27))))
          (number "1" (effects (font (size 1.27 1.27))))
        )
        (pin passive line (at 5.08 0 180) (length 2.032)
          (name "~" (effects (font (size 1.27 1.27))))
          (number "2" (effects (font (size 1.27 1.27))))
        )
      )
    )
	(symbol "antmicroCapacitors0603:C_3u3_0603" (pin_numbers hide) (pin_names hide) (in_bom yes) (on_board yes)
      (property "Reference" "C" (at 20.32 -5.08 0)
        (effects (font (size 1.27 1.27) (thickness 0.15)) (justify left bottom))
      )
      (property "Value" "C_3u3_0603" (at 20.32 -10.16 0)
        (effects (font (size 1.27 1.27) (thickness 0.15)) (justify left bottom) hide)
      )
      (property "Footprint" "antmicro-footprints:C_0603_1608Metric" (at 20.32 -12.7 0)
        (effects (font (size 1.27 1.27) (thickness 0.15)) (justify left bottom) hide)
      )
      (property "Datasheet" "https://www.kemet.com/en/us/capacitors/product/C0603C335M9PACTU.html" (at 20.32 -15.24 0)
        (effects (font (size 1.27 1.27) (thickness 0.15)) (justify left bottom) hide)
      )
      (property "MPN" "C0603C335M9PACTU" (at 20.32 -17.78 0)
        (effects (font (size 1.27 1.27) (thickness 0.15)) (justify left bottom) hide)
      )
      (property "Manufacturer" "KEMET" (at 20.32 -20.32 0)
        (effects (font (size 1.27 1.27) (thickness 0.15)) (justify left bottom) hide)
      )
      (property "License" "Apache-2.0" (at 20.32 -22.86 0)
        (effects (font (size 1.27 1.27) (thickness 0.15)) (justify left bottom) hide)
      )
      (property "Author" "Antmicro" (at 20.32 -25.4 0)
        (effects (font (size 1.27 1.27) (thickness 0.15)) (justify left bottom) hide)
      )
      (property "Val" "3u3" (at 20.32 -7.62 0)
        (effects (font (size 1.27 1.27) (thickness 0.15)) (justify left bottom))
      )
      (property "Voltage" "" (at 20.32 -27.94 0)
        (effects (font (size 1.27 1.27)) (justify left bottom) hide)
      )
      (property "Dielectric" "" (at 20.32 -30.48 0)
        (effects (font (size 1.27 1.27)) (justify left bottom) hide)
      )
      (property "ki_keywords" "0603, SMT, CAPACITOR, PASSIVE, CERAMIC, MLCC" (at 0 0 0)
        (effects (font (size 1.27 1.27)) hide)
      )
      (property "ki_description" "SMD Multilayer Ceramic Capacitor, 3.3 µF, 6.3 V, 0603 [1608 Metric], ± 20%, X5R, C Series KEMET" (at 0 0 0)
        (effects (font (size 1.27 1.27)) hide)
      )
      (symbol "C_3u3_0603_0_1"
        (polyline
          (pts
            (xy 2.032 -1.524)
            (xy 2.032 1.524)
          )
          (stroke (width 0.3048) (type default))
          (fill (type none))
        )
        (polyline
          (pts
            (xy 3.048 -1.524)
            (xy 3.048 1.524)
          )
          (stroke (width 0.3302) (type default))
          (fill (type none))
        )
      )
      (symbol "C_3u3_0603_1_1"
        (pin passive line (at 0 0 0) (length 2.032)
          (name "~" (effects (font (size 1.27 1.27))))
          (number "1" (effects (font (size 1.27 1.27))))
        )
        (pin passive line (at 5.08 0 180) (length 2.032)
          (name "~" (effects (font (size 1.27 1.27))))
          (number "2" (effects (font (size 1.27 1.27))))
        )
      )
    )
	(symbol "antmicroCapacitors0603:C_47u_0603" (pin_numbers hide) (pin_names hide) (in_bom yes) (on_board yes)
      (property "Reference" "C" (at 20.32 -5.08 0)
        (effects (font (size 1.27 1.27) (thickness 0.15)) (justify left bottom))
      )
      (property "Value" "C_47u_0603" (at 20.32 -10.16 0)
        (effects (font (size 1.27 1.27) (thickness 0.15)) (justify left bottom) hide)
      )
      (property "Footprint" "antmicro-footprints:C_0603_1608Metric" (at 20.32 -12.7 0)
        (effects (font (size 1.27 1.27) (thickness 0.15)) (justify left bottom) hide)
      )
      (property "Datasheet" "https://www.murata.com/products/productdetail?partno=GRM188R60J476ME15%23" (at 20.32 -15.24 0)
        (effects (font (size 1.27 1.27) (thickness 0.15)) (justify left bottom) hide)
      )
      (property "MPN" "GRM188R60J476ME15D" (at 20.32 -17.78 0)
        (effects (font (size 1.27 1.27) (thickness 0.15)) (justify left bottom) hide)
      )
      (property "Manufacturer" "Murata" (at 20.32 -20.32 0)
        (effects (font (size 1.27 1.27) (thickness 0.15)) (justify left bottom) hide)
      )
      (property "License" "Apache-2.0" (at 20.32 -22.86 0)
        (effects (font (size 1.27 1.27) (thickness 0.15)) (justify left bottom) hide)
      )
      (property "Author" "Antmicro" (at 20.32 -25.4 0)
        (effects (font (size 1.27 1.27) (thickness 0.15)) (justify left bottom) hide)
      )
      (property "Val" "47u" (at 20.32 -7.62 0)
        (effects (font (size 1.27 1.27) (thickness 0.15)) (justify left bottom))
      )
      (property "Voltage" "" (at 20.32 -27.94 0)
        (effects (font (size 1.27 1.27)) (justify left bottom) hide)
      )
      (property "Dielectric" "" (at 20.32 -30.48 0)
        (effects (font (size 1.27 1.27)) (justify left bottom) hide)
      )
      (property "ki_keywords" "0603, SMT, CAPACITOR, PASSIVE, CERAMIC, MLCC" (at 0 0 0)
        (effects (font (size 1.27 1.27)) hide)
      )
      (property "ki_description" "SMD Multilayer Ceramic Capacitor, 47 µF, 6.3 V, 0603 [1608 Metric], ± 20%, X5R, GRM Series" (at 0 0 0)
        (effects (font (size 1.27 1.27)) hide)
      )
      (symbol "C_47u_0603_0_1"
        (polyline
          (pts
            (xy 2.032 -1.524)
            (xy 2.032 1.524)
          )
          (stroke (width 0.3048) (type default))
          (fill (type none))
        )
        (polyline
          (pts
            (xy 3.048 -1.524)
            (xy 3.048 1.524)
          )
          (stroke (width 0.3302) (type default))
          (fill (type none))
        )
      )
      (symbol "C_47u_0603_1_1"
        (pin passive line (at 0 0 0) (length 2.032)
          (name "~" (effects (font (size 1.27 1.27))))
          (number "1" (effects (font (size 1.27 1.27))))
        )
        (pin passive line (at 5.08 0 180) (length 2.032)
          (name "~" (effects (font (size 1.27 1.27))))
          (number "2" (effects (font (size 1.27 1.27))))
        )
      )
    )
	(symbol "antmicroCapacitorsmisc:C_10u_0805" (pin_numbers hide) (pin_names hide) (in_bom yes) (on_board yes)
      (property "Reference" "C" (at 20.32 -5.08 0)
        (effects (font (size 1.27 1.27) (thickness 0.15)) (justify left bottom))
      )
      (property "Value" "C_10u_0805" (at 20.32 -10.16 0)
        (effects (font (size 1.27 1.27) (thickness 0.15)) (justify left bottom) hide)
      )
      (property "Footprint" "antmicro-footprints:C_0805_2012Metric" (at 20.32 -12.7 0)
        (effects (font (size 1.27 1.27) (thickness 0.15)) (justify left bottom) hide)
      )
      (property "Datasheet" "https://www.johansontechnology.com/index.php?option=com_jtiproducts&name=160R15X106KV4E" (at 20.32 -15.24 0)
        (effects (font (size 1.27 1.27) (thickness 0.15)) (justify left bottom) hide)
      )
      (property "MPN" "160R15X106KV4E" (at 20.32 -17.78 0)
        (effects (font (size 1.27 1.27) (thickness 0.15)) (justify left bottom) hide)
      )
      (property "Manufacturer" "Johanson Technology" (at 20.32 -20.32 0)
        (effects (font (size 1.27 1.27) (thickness 0.15)) (justify left bottom) hide)
      )
      (property "License" "Apache-2.0" (at 20.32 -22.86 0)
        (effects (font (size 1.27 1.27) (thickness 0.15)) (justify left bottom) hide)
      )
      (property "Author" "Antmicro" (at 20.32 -25.4 0)
        (effects (font (size 1.27 1.27) (thickness 0.15)) (justify left bottom) hide)
      )
      (property "Val" "10u" (at 20.32 -7.62 0)
        (effects (font (size 1.27 1.27) (thickness 0.15)) (justify left bottom))
      )
      (property "Voltage" "" (at 20.32 -27.94 0)
        (effects (font (size 1.27 1.27)) (justify left bottom) hide)
      )
      (property "Dielectric" "" (at 20.32 -30.48 0)
        (effects (font (size 1.27 1.27)) (justify left bottom) hide)
      )
      (property "ki_keywords" "0805, SMT, CAPACITOR, PASSIVE" (at 0 0 0)
        (effects (font (size 1.27 1.27)) hide)
      )
      (property "ki_description" "SMD Multilayer Ceramic Capacitor, TANCERAM®, 10 µF, 16 V, 0805 [2012 Metric], ± 10%, X5R" (at 0 0 0)
        (effects (font (size 1.27 1.27)) hide)
      )
      (symbol "C_10u_0805_0_1"
        (polyline
          (pts
            (xy 2.032 -1.524)
            (xy 2.032 1.524)
          )
          (stroke (width 0.3048) (type default))
          (fill (type none))
        )
        (polyline
          (pts
            (xy 3.048 -1.524)
            (xy 3.048 1.524)
          )
          (stroke (width 0.3302) (type default))
          (fill (type none))
        )
      )
      (symbol "C_10u_0805_1_1"
        (pin passive line (at 0 0 0) (length 2.032)
          (name "~" (effects (font (size 1.27 1.27))))
          (number "1" (effects (font (size 1.27 1.27))))
        )
        (pin passive line (at 5.08 0 180) (length 2.032)
          (name "~" (effects (font (size 1.27 1.27))))
          (number "2" (effects (font (size 1.27 1.27))))
        )
      )
    )
	(symbol "antmicroCapacitorsmisc:C_47u_1210" (pin_numbers hide) (pin_names hide) (in_bom yes) (on_board yes)
      (property "Reference" "C" (at 20.32 -5.08 0)
        (effects (font (size 1.27 1.27) (thickness 0.15)) (justify left bottom))
      )
      (property "Value" "C_47u_1210" (at 20.32 -10.16 0)
        (effects (font (size 1.27 1.27) (thickness 0.15)) (justify left bottom) hide)
      )
      (property "Footprint" "antmicro-footprints:C_1210_3225Metric" (at 20.32 -12.7 0)
        (effects (font (size 1.27 1.27) (thickness 0.15)) (justify left bottom) hide)
      )
      (property "Datasheet" "https://www.kemet.com/en/us/capacitors/product/C1210C476K8RACTU.html" (at 20.32 -15.24 0)
        (effects (font (size 1.27 1.27) (thickness 0.15)) (justify left bottom) hide)
      )
      (property "MPN" "C1210C476K8RACTU" (at 20.32 -17.78 0)
        (effects (font (size 1.27 1.27) (thickness 0.15)) (justify left bottom) hide)
      )
      (property "Manufacturer" "KEMET" (at 20.32 -20.32 0)
        (effects (font (size 1.27 1.27) (thickness 0.15)) (justify left bottom) hide)
      )
      (property "License" "Apache-2.0" (at 20.32 -22.86 0)
        (effects (font (size 1.27 1.27) (thickness 0.15)) (justify left bottom) hide)
      )
      (property "Author" "Antmicro" (at 20.32 -25.4 0)
        (effects (font (size 1.27 1.27) (thickness 0.15)) (justify left bottom) hide)
      )
      (property "Val" "47u" (at 20.32 -7.62 0)
        (effects (font (size 1.27 1.27) (thickness 0.15)) (justify left bottom))
      )
      (property "Voltage" "" (at 20.32 -27.94 0)
        (effects (font (size 1.27 1.27)) (justify left bottom) hide)
      )
      (property "Dielectric" "" (at 20.32 -30.48 0)
        (effects (font (size 1.27 1.27)) (justify left bottom) hide)
      )
      (property "ki_keywords" "1210, SMT, CAPACITOR, PASSIVE" (at 0 0 0)
        (effects (font (size 1.27 1.27)) hide)
      )
      (property "ki_description" "SMD Multilayer Ceramic Capacitor, 47 µF, 10 V, 1210 [3225 Metric], ± 10%, X7R, C Series KEMET" (at 0 0 0)
        (effects (font (size 1.27 1.27)) hide)
      )
      (symbol "C_47u_1210_0_1"
        (polyline
          (pts
            (xy 2.032 -1.524)
            (xy 2.032 1.524)
          )
          (stroke (width 0.3048) (type default))
          (fill (type none))
        )
        (polyline
          (pts
            (xy 3.048 -1.524)
            (xy 3.048 1.524)
          )
          (stroke (width 0.3302) (type default))
          (fill (type none))
        )
      )
      (symbol "C_47u_1210_1_1"
        (pin passive line (at 0 0 0) (length 2.032)
          (name "~" (effects (font (size 1.27 1.27))))
          (number "1" (effects (font (size 1.27 1.27))))
        )
        (pin passive line (at 5.08 0 180) (length 2.032)
          (name "~" (effects (font (size 1.27 1.27))))
          (number "2" (effects (font (size 1.27 1.27))))
        )
      )
    )
	(symbol "antmicroDCDCConverters:TPS62823DLCT" (pin_names (offset 1.016)) (in_bom yes) (on_board yes)
      (property "Reference" "U" (at 34.29 1.27 0)
        (effects (font (size 1.27 1.27) (thickness 0.15)) (justify left bottom))
      )
      (property "Value" "TPS62823DLCT" (at 34.29 -1.27 0)
        (effects (font (size 1.27 1.27) (thickness 0.15)) (justify left bottom) hide)
      )
      (property "Footprint" "antmicro-footprints:QFN-8_2x1.5mm" (at 34.29 -3.81 0)
        (effects (font (size 1.27 1.27) (thickness 0.15)) (justify left bottom) hide)
      )
      (property "Datasheet" "https://www.ti.com/lit/ds/symlink/tps62823.pdf?ts=1685970309606&ref_url=https%253A%252F%252Fwww.ti.com%252Fproduct%252FTPS62823%252Fpart-details%252FTPS62823DLCT" (at 34.29 -6.35 0)
        (effects (font (size 1.27 1.27) (thickness 0.15)) (justify left bottom) hide)
      )
      (property "MPN" "TPS62823DLCT" (at 34.29 -8.89 0)
        (effects (font (size 1.27 1.27) (thickness 0.15)) (justify left bottom))
      )
      (property "Manufacturer" "Texas Instruments" (at 34.29 -11.43 0)
        (effects (font (size 1.27 1.27) (thickness 0.15)) (justify left bottom) hide)
      )
      (property "Author" "Antmicro" (at 34.29 -13.97 0)
        (effects (font (size 1.27 1.27) (thickness 0.15)) (justify left bottom) hide)
      )
      (property "License" "Apache-2.0" (at 34.29 -16.51 0)
        (effects (font (size 1.27 1.27) (thickness 0.15)) (justify left bottom) hide)
      )
      (property "ki_keywords" "SMT, PMIC, IC, SWITCHING, VOLTAGE, REGULATOR, DC-DC" (at 0 0 0)
        (effects (font (size 1.27 1.27)) hide)
      )
      (property "ki_description" "DC/DC converter" (at 0 0 0)
        (effects (font (size 1.27 1.27)) hide)
      )
      (symbol "TPS62823DLCT_0_0"
        (pin no_connect line (at 17.78 -2.54 180) (length 2.54) hide
          (name "NC" (effects (font (size 1.27 1.27))))
          (number "4" (effects (font (size 1.27 1.27))))
        )
      )
      (symbol "TPS62823DLCT_0_1"
        (rectangle (start 2.54 2.54) (end 17.78 -15.24)
          (stroke (width 0) (type default))
          (fill (type background))
        )
      )
      (symbol "TPS62823DLCT_1_1"
        (pin input line (at 0 -6.35 0) (length 2.54)
          (name "EN" (effects (font (size 1.27 1.27))))
          (number "1" (effects (font (size 1.27 1.27))))
        )
        (pin bidirectional line (at 20.32 -6.35 180) (length 2.54)
          (name "FB" (effects (font (size 1.27 1.27))))
          (number "2" (effects (font (size 1.27 1.27))))
        )
        (pin power_in line (at 20.32 -10.16 180) (length 2.54)
          (name "AGND" (effects (font (size 1.27 1.27))))
          (number "3" (effects (font (size 1.27 1.27))))
        )
        (pin power_in line (at 20.32 -12.7 180) (length 2.54)
          (name "PGND" (effects (font (size 1.27 1.27))))
          (number "5" (effects (font (size 1.27 1.27))))
        )
        (pin bidirectional line (at 20.32 0 180) (length 2.54)
          (name "SW" (effects (font (size 1.27 1.27))))
          (number "6" (effects (font (size 1.27 1.27))))
        )
        (pin power_in line (at 0 0 0) (length 2.54)
          (name "VIN" (effects (font (size 1.27 1.27))))
          (number "7" (effects (font (size 1.27 1.27))))
        )
        (pin output line (at 0 -12.7 0) (length 2.54)
          (name "PG" (effects (font (size 1.27 1.27))))
          (number "8" (effects (font (size 1.27 1.27))))
        )
      )
    )
	(symbol "antmicroFPGAChips:ECP5_LFE5UM5G-85" (in_bom yes) (on_board yes)
      (property "Reference" "U" (at 77.47 -3.81 0)
        (effects (font (size 1.27 1.27) (thickness 0.15)) (justify left bottom))
      )
      (property "Value" "ECP5_LFE5UM5G-85" (at 77.47 -8.89 0)
        (effects (font (size 1.27 1.27) (thickness 0.15)) (justify left bottom) hide)
      )
      (property "Footprint" "antmicro-footprints:BGA-1024-756_27x27mm_Layout32x32_P0.8mm" (at 77.47 -11.43 0)
        (effects (font (size 1.27 1.27) (thickness 0.15)) (justify left bottom) hide)
      )
      (property "Datasheet" "https://www.latticesemi.com/-/media/LatticeSemi/Documents/DataSheets/ECP5/FPGA-DS-02012-2-2-ECP5-ECP5G-Family-Data-Sheet.ashx?document_id=50461" (at 77.47 -13.97 0)
        (effects (font (size 1.27 1.27) (thickness 0.15)) (justify left bottom) hide)
      )
      (property "MPN" "LFE5UM5G-85F-8BG756C" (at 77.47 -6.35 0)
        (effects (font (size 1.27 1.27) (thickness 0.15)) (justify left bottom))
      )
      (property "Manufacturer" "Lattice Semiconductor" (at 77.47 -16.51 0)
        (effects (font (size 1.27 1.27) (thickness 0.15)) (justify left bottom) hide)
      )
      (property "Author" "Antmicro" (at 77.47 -19.05 0)
        (effects (font (size 1.27 1.27) (thickness 0.15)) (justify left bottom) hide)
      )
      (property "License" "Apache-2.0" (at 77.47 -21.59 0)
        (effects (font (size 1.27 1.27) (thickness 0.15)) (justify left bottom) hide)
      )
      (property "ki_locked" "" (at 0 0 0)
        (effects (font (size 1.27 1.27)))
      )
      (property "ki_keywords" "SMT, FPGA, IC" (at 0 0 0)
        (effects (font (size 1.27 1.27)) hide)
      )
      (property "ki_description" "ECP5-5G Field Programmable Gate Array" (at 0 0 0)
        (effects (font (size 1.27 1.27)) hide)
      )
      (symbol "ECP5_LFE5UM5G-85_1_1"
        (rectangle (start 5.08 2.54) (end 33.02 -43.18)
          (stroke (width 0.254) (type default))
          (fill (type background))
        )
        (pin power_in line (at 38.1 -40.64 180) (length 5.08)
          (name "GND" (effects (font (size 1.27 1.27))))
          (number "AA11" (effects (font (size 1.27 1.27))))
        )
        (pin power_in line (at 0 0 0) (length 5.08)
          (name "VCC" (effects (font (size 1.27 1.27))))
          (number "AA12" (effects (font (size 1.27 1.27))))
        )
        (pin passive line (at 0 0 0) (length 5.08) hide
          (name "VCC" (effects (font (size 1.27 1.27))))
          (number "AA13" (effects (font (size 1.27 1.27))))
        )
        (pin passive line (at 0 0 0) (length 5.08) hide
          (name "VCC" (effects (font (size 1.27 1.27))))
          (number "AA14" (effects (font (size 1.27 1.27))))
        )
        (pin passive line (at 0 0 0) (length 5.08) hide
          (name "VCC" (effects (font (size 1.27 1.27))))
          (number "AA15" (effects (font (size 1.27 1.27))))
        )
        (pin passive line (at 0 0 0) (length 5.08) hide
          (name "VCC" (effects (font (size 1.27 1.27))))
          (number "AA16" (effects (font (size 1.27 1.27))))
        )
        (pin passive line (at 0 0 0) (length 5.08) hide
          (name "VCC" (effects (font (size 1.27 1.27))))
          (number "AA17" (effects (font (size 1.27 1.27))))
        )
        (pin passive line (at 0 0 0) (length 5.08) hide
          (name "VCC" (effects (font (size 1.27 1.27))))
          (number "AA18" (effects (font (size 1.27 1.27))))
        )
        (pin passive line (at 0 0 0) (length 5.08) hide
          (name "VCC" (effects (font (size 1.27 1.27))))
          (number "AA19" (effects (font (size 1.27 1.27))))
        )
        (pin passive line (at 0 0 0) (length 5.08) hide
          (name "VCC" (effects (font (size 1.27 1.27))))
          (number "AA20" (effects (font (size 1.27 1.27))))
        )
        (pin passive line (at 0 0 0) (length 5.08) hide
          (name "VCC" (effects (font (size 1.27 1.27))))
          (number "AA21" (effects (font (size 1.27 1.27))))
        )
        (pin passive line (at 38.1 -40.64 180) (length 5.08) hide
          (name "GND" (effects (font (size 1.27 1.27))))
          (number "AA22" (effects (font (size 1.27 1.27))))
        )
        (pin passive line (at 38.1 -40.64 180) (length 5.08) hide
          (name "GND" (effects (font (size 1.27 1.27))))
          (number "AB11" (effects (font (size 1.27 1.27))))
        )
        (pin passive line (at 38.1 -40.64 180) (length 5.08) hide
          (name "GND" (effects (font (size 1.27 1.27))))
          (number "AB12" (effects (font (size 1.27 1.27))))
        )
        (pin passive line (at 38.1 -40.64 180) (length 5.08) hide
          (name "GND" (effects (font (size 1.27 1.27))))
          (number "AB13" (effects (font (size 1.27 1.27))))
        )
        (pin passive line (at 38.1 -40.64 180) (length 5.08) hide
          (name "GND" (effects (font (size 1.27 1.27))))
          (number "AB14" (effects (font (size 1.27 1.27))))
        )
        (pin passive line (at 38.1 -40.64 180) (length 5.08) hide
          (name "GND" (effects (font (size 1.27 1.27))))
          (number "AB15" (effects (font (size 1.27 1.27))))
        )
        (pin passive line (at 38.1 -40.64 180) (length 5.08) hide
          (name "GND" (effects (font (size 1.27 1.27))))
          (number "AB16" (effects (font (size 1.27 1.27))))
        )
        (pin passive line (at 38.1 -40.64 180) (length 5.08) hide
          (name "GND" (effects (font (size 1.27 1.27))))
          (number "AB17" (effects (font (size 1.27 1.27))))
        )
        (pin passive line (at 38.1 -40.64 180) (length 5.08) hide
          (name "GND" (effects (font (size 1.27 1.27))))
          (number "AB18" (effects (font (size 1.27 1.27))))
        )
        (pin passive line (at 38.1 -40.64 180) (length 5.08) hide
          (name "GND" (effects (font (size 1.27 1.27))))
          (number "AB19" (effects (font (size 1.27 1.27))))
        )
        (pin passive line (at 38.1 -40.64 180) (length 5.08) hide
          (name "GND" (effects (font (size 1.27 1.27))))
          (number "AB20" (effects (font (size 1.27 1.27))))
        )
        (pin passive line (at 38.1 -40.64 180) (length 5.08) hide
          (name "GND" (effects (font (size 1.27 1.27))))
          (number "AB21" (effects (font (size 1.27 1.27))))
        )
        (pin passive line (at 38.1 -40.64 180) (length 5.08) hide
          (name "GND" (effects (font (size 1.27 1.27))))
          (number "AB22" (effects (font (size 1.27 1.27))))
        )
        (pin power_in line (at 0 -8.89 0) (length 5.08)
          (name "VCCAUX" (effects (font (size 1.27 1.27))))
          (number "AC11" (effects (font (size 1.27 1.27))))
        )
        (pin passive line (at 38.1 -40.64 180) (length 5.08) hide
          (name "GND" (effects (font (size 1.27 1.27))))
          (number "AC12" (effects (font (size 1.27 1.27))))
        )
        (pin power_in line (at 38.1 -2.54 180) (length 5.08)
          (name "VCCHTX0_D0CH0" (effects (font (size 1.27 1.27))))
          (number "AC13" (effects (font (size 1.27 1.27))))
        )
        (pin power_in line (at 38.1 -7.62 180) (length 5.08)
          (name "VCCHRX0_D0CH0" (effects (font (size 1.27 1.27))))
          (number "AC14" (effects (font (size 1.27 1.27))))
        )
        (pin power_in line (at 38.1 -17.78 180) (length 5.08)
          (name "VCCHRX1_D0CH1" (effects (font (size 1.27 1.27))))
          (number "AC15" (effects (font (size 1.27 1.27))))
        )
        (pin power_in line (at 38.1 -12.7 180) (length 5.08)
          (name "VCCHTX1_D0CH1" (effects (font (size 1.27 1.27))))
          (number "AC16" (effects (font (size 1.27 1.27))))
        )
        (pin power_in line (at 38.1 0 180) (length 5.08)
          (name "VCCHTX0_D1CH0" (effects (font (size 1.27 1.27))))
          (number "AC17" (effects (font (size 1.27 1.27))))
        )
        (pin power_in line (at 38.1 -5.08 180) (length 5.08)
          (name "VCCHRX0_D1CH0" (effects (font (size 1.27 1.27))))
          (number "AC18" (effects (font (size 1.27 1.27))))
        )
        (pin power_in line (at 38.1 -15.24 180) (length 5.08)
          (name "VCCHRX1_D1CH1" (effects (font (size 1.27 1.27))))
          (number "AC19" (effects (font (size 1.27 1.27))))
        )
        (pin power_in line (at 38.1 -10.16 180) (length 5.08)
          (name "VCCHTX1_D1CH1" (effects (font (size 1.27 1.27))))
          (number "AC20" (effects (font (size 1.27 1.27))))
        )
        (pin passive line (at 38.1 -40.64 180) (length 5.08) hide
          (name "GND" (effects (font (size 1.27 1.27))))
          (number "AC21" (effects (font (size 1.27 1.27))))
        )
        (pin passive line (at 0 -8.89 0) (length 5.08) hide
          (name "VCCAUX" (effects (font (size 1.27 1.27))))
          (number "AC22" (effects (font (size 1.27 1.27))))
        )
        (pin no_connect line (at 33.02 -20.32 180) (length 5.08) hide
          (name "NC" (effects (font (size 1.27 1.27))))
          (number "AC29" (effects (font (size 1.27 1.27))))
        )
        (pin no_connect line (at 33.02 -21.59 180) (length 5.08) hide
          (name "NC" (effects (font (size 1.27 1.27))))
          (number "AC4" (effects (font (size 1.27 1.27))))
        )
        (pin passive line (at 38.1 -40.64 180) (length 5.08) hide
          (name "GND" (effects (font (size 1.27 1.27))))
          (number "AD2" (effects (font (size 1.27 1.27))))
        )
        (pin passive line (at 38.1 -40.64 180) (length 5.08) hide
          (name "GND" (effects (font (size 1.27 1.27))))
          (number "AD28" (effects (font (size 1.27 1.27))))
        )
        (pin passive line (at 38.1 -40.64 180) (length 5.08) hide
          (name "GND" (effects (font (size 1.27 1.27))))
          (number "AD31" (effects (font (size 1.27 1.27))))
        )
        (pin passive line (at 38.1 -40.64 180) (length 5.08) hide
          (name "GND" (effects (font (size 1.27 1.27))))
          (number "AD5" (effects (font (size 1.27 1.27))))
        )
        (pin no_connect line (at 33.02 -22.86 180) (length 5.08) hide
          (name "NC" (effects (font (size 1.27 1.27))))
          (number "AE26" (effects (font (size 1.27 1.27))))
        )
        (pin no_connect line (at 33.02 -24.13 180) (length 5.08) hide
          (name "NC" (effects (font (size 1.27 1.27))))
          (number "AE7" (effects (font (size 1.27 1.27))))
        )
        (pin passive line (at 38.1 -40.64 180) (length 5.08) hide
          (name "GND" (effects (font (size 1.27 1.27))))
          (number "AF11" (effects (font (size 1.27 1.27))))
        )
        (pin passive line (at 38.1 -40.64 180) (length 5.08) hide
          (name "GND" (effects (font (size 1.27 1.27))))
          (number "AF12" (effects (font (size 1.27 1.27))))
        )
        (pin passive line (at 38.1 -40.64 180) (length 5.08) hide
          (name "GND" (effects (font (size 1.27 1.27))))
          (number "AF14" (effects (font (size 1.27 1.27))))
        )
        (pin passive line (at 38.1 -40.64 180) (length 5.08) hide
          (name "GND" (effects (font (size 1.27 1.27))))
          (number "AF15" (effects (font (size 1.27 1.27))))
        )
        (pin passive line (at 38.1 -40.64 180) (length 5.08) hide
          (name "GND" (effects (font (size 1.27 1.27))))
          (number "AF16" (effects (font (size 1.27 1.27))))
        )
        (pin passive line (at 38.1 -40.64 180) (length 5.08) hide
          (name "GND" (effects (font (size 1.27 1.27))))
          (number "AF17" (effects (font (size 1.27 1.27))))
        )
        (pin passive line (at 38.1 -40.64 180) (length 5.08) hide
          (name "GND" (effects (font (size 1.27 1.27))))
          (number "AF19" (effects (font (size 1.27 1.27))))
        )
        (pin passive line (at 38.1 -40.64 180) (length 5.08) hide
          (name "GND" (effects (font (size 1.27 1.27))))
          (number "AF20" (effects (font (size 1.27 1.27))))
        )
        (pin power_in line (at 0 -5.08 0) (length 5.08)
          (name "VCCA1" (effects (font (size 1.27 1.27))))
          (number "AF22" (effects (font (size 1.27 1.27))))
        )
        (pin passive line (at 38.1 -40.64 180) (length 5.08) hide
          (name "GND" (effects (font (size 1.27 1.27))))
          (number "AF23" (effects (font (size 1.27 1.27))))
        )
        (pin passive line (at 38.1 -40.64 180) (length 5.08) hide
          (name "GND" (effects (font (size 1.27 1.27))))
          (number "AG11" (effects (font (size 1.27 1.27))))
        )
        (pin power_in line (at 0 -2.54 0) (length 5.08)
          (name "VCCA0" (effects (font (size 1.27 1.27))))
          (number "AG12" (effects (font (size 1.27 1.27))))
        )
        (pin passive line (at 38.1 -40.64 180) (length 5.08) hide
          (name "GND" (effects (font (size 1.27 1.27))))
          (number "AG14" (effects (font (size 1.27 1.27))))
        )
        (pin passive line (at 38.1 -40.64 180) (length 5.08) hide
          (name "GND" (effects (font (size 1.27 1.27))))
          (number "AG15" (effects (font (size 1.27 1.27))))
        )
        (pin passive line (at 38.1 -40.64 180) (length 5.08) hide
          (name "GND" (effects (font (size 1.27 1.27))))
          (number "AG16" (effects (font (size 1.27 1.27))))
        )
        (pin passive line (at 38.1 -40.64 180) (length 5.08) hide
          (name "GND" (effects (font (size 1.27 1.27))))
          (number "AG17" (effects (font (size 1.27 1.27))))
        )
        (pin passive line (at 0 -5.08 0) (length 5.08) hide
          (name "VCCA1" (effects (font (size 1.27 1.27))))
          (number "AG19" (effects (font (size 1.27 1.27))))
        )
        (pin no_connect line (at 33.02 -25.4 180) (length 5.08) hide
          (name "NC" (effects (font (size 1.27 1.27))))
          (number "AG2" (effects (font (size 1.27 1.27))))
        )
        (pin passive line (at 38.1 -40.64 180) (length 5.08) hide
          (name "GND" (effects (font (size 1.27 1.27))))
          (number "AG20" (effects (font (size 1.27 1.27))))
        )
        (pin passive line (at 0 -5.08 0) (length 5.08) hide
          (name "VCCA1" (effects (font (size 1.27 1.27))))
          (number "AG22" (effects (font (size 1.27 1.27))))
        )
        (pin passive line (at 38.1 -40.64 180) (length 5.08) hide
          (name "GND" (effects (font (size 1.27 1.27))))
          (number "AG23" (effects (font (size 1.27 1.27))))
        )
        (pin no_connect line (at 33.02 -26.67 180) (length 5.08) hide
          (name "NC" (effects (font (size 1.27 1.27))))
          (number "AG24" (effects (font (size 1.27 1.27))))
        )
        (pin no_connect line (at 33.02 -27.94 180) (length 5.08) hide
          (name "NC" (effects (font (size 1.27 1.27))))
          (number "AG31" (effects (font (size 1.27 1.27))))
        )
        (pin passive line (at 0 -2.54 0) (length 5.08) hide
          (name "VCCA0" (effects (font (size 1.27 1.27))))
          (number "AG9" (effects (font (size 1.27 1.27))))
        )
        (pin passive line (at 38.1 -40.64 180) (length 5.08) hide
          (name "GND" (effects (font (size 1.27 1.27))))
          (number "AH11" (effects (font (size 1.27 1.27))))
        )
        (pin passive line (at 0 -2.54 0) (length 5.08) hide
          (name "VCCA0" (effects (font (size 1.27 1.27))))
          (number "AH12" (effects (font (size 1.27 1.27))))
        )
        (pin passive line (at 38.1 -40.64 180) (length 5.08) hide
          (name "GND" (effects (font (size 1.27 1.27))))
          (number "AH14" (effects (font (size 1.27 1.27))))
        )
        (pin passive line (at 38.1 -40.64 180) (length 5.08) hide
          (name "GND" (effects (font (size 1.27 1.27))))
          (number "AH15" (effects (font (size 1.27 1.27))))
        )
        (pin passive line (at 38.1 -40.64 180) (length 5.08) hide
          (name "GND" (effects (font (size 1.27 1.27))))
          (number "AH16" (effects (font (size 1.27 1.27))))
        )
        (pin passive line (at 38.1 -40.64 180) (length 5.08) hide
          (name "GND" (effects (font (size 1.27 1.27))))
          (number "AH17" (effects (font (size 1.27 1.27))))
        )
        (pin passive line (at 0 -5.08 0) (length 5.08) hide
          (name "VCCA1" (effects (font (size 1.27 1.27))))
          (number "AH19" (effects (font (size 1.27 1.27))))
        )
        (pin passive line (at 38.1 -40.64 180) (length 5.08) hide
          (name "GND" (effects (font (size 1.27 1.27))))
          (number "AH2" (effects (font (size 1.27 1.27))))
        )
        (pin passive line (at 38.1 -40.64 180) (length 5.08) hide
          (name "GND" (effects (font (size 1.27 1.27))))
          (number "AH20" (effects (font (size 1.27 1.27))))
        )
        (pin passive line (at 0 -5.08 0) (length 5.08) hide
          (name "VCCA1" (effects (font (size 1.27 1.27))))
          (number "AH22" (effects (font (size 1.27 1.27))))
        )
        (pin passive line (at 38.1 -40.64 180) (length 5.08) hide
          (name "GND" (effects (font (size 1.27 1.27))))
          (number "AH23" (effects (font (size 1.27 1.27))))
        )
        (pin passive line (at 38.1 -40.64 180) (length 5.08) hide
          (name "GND" (effects (font (size 1.27 1.27))))
          (number "AH24" (effects (font (size 1.27 1.27))))
        )
        (pin passive line (at 38.1 -40.64 180) (length 5.08) hide
          (name "GND" (effects (font (size 1.27 1.27))))
          (number "AH25" (effects (font (size 1.27 1.27))))
        )
        (pin passive line (at 38.1 -40.64 180) (length 5.08) hide
          (name "GND" (effects (font (size 1.27 1.27))))
          (number "AH26" (effects (font (size 1.27 1.27))))
        )
        (pin passive line (at 38.1 -40.64 180) (length 5.08) hide
          (name "GND" (effects (font (size 1.27 1.27))))
          (number "AH29" (effects (font (size 1.27 1.27))))
        )
        (pin passive line (at 38.1 -40.64 180) (length 5.08) hide
          (name "GND" (effects (font (size 1.27 1.27))))
          (number "AH31" (effects (font (size 1.27 1.27))))
        )
        (pin passive line (at 38.1 -40.64 180) (length 5.08) hide
          (name "GND" (effects (font (size 1.27 1.27))))
          (number "AH5" (effects (font (size 1.27 1.27))))
        )
        (pin passive line (at 38.1 -40.64 180) (length 5.08) hide
          (name "GND" (effects (font (size 1.27 1.27))))
          (number "AH7" (effects (font (size 1.27 1.27))))
        )
        (pin passive line (at 38.1 -40.64 180) (length 5.08) hide
          (name "GND" (effects (font (size 1.27 1.27))))
          (number "AH8" (effects (font (size 1.27 1.27))))
        )
        (pin passive line (at 0 -2.54 0) (length 5.08) hide
          (name "VCCA0" (effects (font (size 1.27 1.27))))
          (number "AH9" (effects (font (size 1.27 1.27))))
        )
        (pin passive line (at 0 -2.54 0) (length 5.08) hide
          (name "VCCA0" (effects (font (size 1.27 1.27))))
          (number "AJ10" (effects (font (size 1.27 1.27))))
        )
        (pin passive line (at 38.1 -40.64 180) (length 5.08) hide
          (name "GND" (effects (font (size 1.27 1.27))))
          (number "AJ11" (effects (font (size 1.27 1.27))))
        )
        (pin passive line (at 0 -2.54 0) (length 5.08) hide
          (name "VCCA0" (effects (font (size 1.27 1.27))))
          (number "AJ12" (effects (font (size 1.27 1.27))))
        )
        (pin passive line (at 0 -2.54 0) (length 5.08) hide
          (name "VCCA0" (effects (font (size 1.27 1.27))))
          (number "AJ13" (effects (font (size 1.27 1.27))))
        )
        (pin passive line (at 38.1 -40.64 180) (length 5.08) hide
          (name "GND" (effects (font (size 1.27 1.27))))
          (number "AJ14" (effects (font (size 1.27 1.27))))
        )
        (pin power_in line (at 0 -11.43 0) (length 5.08)
          (name "VCCAUXA0" (effects (font (size 1.27 1.27))))
          (number "AJ15" (effects (font (size 1.27 1.27))))
        )
        (pin passive line (at 0 -11.43 0) (length 5.08) hide
          (name "VCCAUXA0" (effects (font (size 1.27 1.27))))
          (number "AJ16" (effects (font (size 1.27 1.27))))
        )
        (pin passive line (at 38.1 -40.64 180) (length 5.08) hide
          (name "GND" (effects (font (size 1.27 1.27))))
          (number "AJ17" (effects (font (size 1.27 1.27))))
        )
        (pin passive line (at 0 -5.08 0) (length 5.08) hide
          (name "VCCA1" (effects (font (size 1.27 1.27))))
          (number "AJ18" (effects (font (size 1.27 1.27))))
        )
        (pin passive line (at 0 -5.08 0) (length 5.08) hide
          (name "VCCA1" (effects (font (size 1.27 1.27))))
          (number "AJ19" (effects (font (size 1.27 1.27))))
        )
        (pin passive line (at 38.1 -40.64 180) (length 5.08) hide
          (name "GND" (effects (font (size 1.27 1.27))))
          (number "AJ20" (effects (font (size 1.27 1.27))))
        )
        (pin passive line (at 0 -5.08 0) (length 5.08) hide
          (name "VCCA1" (effects (font (size 1.27 1.27))))
          (number "AJ21" (effects (font (size 1.27 1.27))))
        )
        (pin passive line (at 0 -5.08 0) (length 5.08) hide
          (name "VCCA1" (effects (font (size 1.27 1.27))))
          (number "AJ22" (effects (font (size 1.27 1.27))))
        )
        (pin passive line (at 38.1 -40.64 180) (length 5.08) hide
          (name "GND" (effects (font (size 1.27 1.27))))
          (number "AJ23" (effects (font (size 1.27 1.27))))
        )
        (pin power_in line (at 0 -13.97 0) (length 5.08)
          (name "VCCAUXA1" (effects (font (size 1.27 1.27))))
          (number "AJ24" (effects (font (size 1.27 1.27))))
        )
        (pin passive line (at 0 -13.97 0) (length 5.08) hide
          (name "VCCAUXA1" (effects (font (size 1.27 1.27))))
          (number "AJ25" (effects (font (size 1.27 1.27))))
        )
        (pin passive line (at 38.1 -40.64 180) (length 5.08) hide
          (name "GND" (effects (font (size 1.27 1.27))))
          (number "AJ26" (effects (font (size 1.27 1.27))))
        )
        (pin passive line (at 38.1 -40.64 180) (length 5.08) hide
          (name "GND" (effects (font (size 1.27 1.27))))
          (number "AJ7" (effects (font (size 1.27 1.27))))
        )
        (pin passive line (at 38.1 -40.64 180) (length 5.08) hide
          (name "GND" (effects (font (size 1.27 1.27))))
          (number "AJ8" (effects (font (size 1.27 1.27))))
        )
        (pin passive line (at 0 -2.54 0) (length 5.08) hide
          (name "VCCA0" (effects (font (size 1.27 1.27))))
          (number "AJ9" (effects (font (size 1.27 1.27))))
        )
        (pin passive line (at 38.1 -40.64 180) (length 5.08) hide
          (name "GND" (effects (font (size 1.27 1.27))))
          (number "AK11" (effects (font (size 1.27 1.27))))
        )
        (pin passive line (at 38.1 -40.64 180) (length 5.08) hide
          (name "GND" (effects (font (size 1.27 1.27))))
          (number "AK14" (effects (font (size 1.27 1.27))))
        )
        (pin no_connect line (at 5.08 -34.29 0) (length 5.08) hide
          (name "RESERVED" (effects (font (size 1.27 1.27))))
          (number "AK15" (effects (font (size 1.27 1.27))))
        )
        (pin no_connect line (at 5.08 -35.56 0) (length 5.08) hide
          (name "RESERVED" (effects (font (size 1.27 1.27))))
          (number "AK16" (effects (font (size 1.27 1.27))))
        )
        (pin passive line (at 38.1 -40.64 180) (length 5.08) hide
          (name "GND" (effects (font (size 1.27 1.27))))
          (number "AK17" (effects (font (size 1.27 1.27))))
        )
        (pin passive line (at 38.1 -40.64 180) (length 5.08) hide
          (name "GND" (effects (font (size 1.27 1.27))))
          (number "AK20" (effects (font (size 1.27 1.27))))
        )
        (pin passive line (at 38.1 -40.64 180) (length 5.08) hide
          (name "GND" (effects (font (size 1.27 1.27))))
          (number "AK23" (effects (font (size 1.27 1.27))))
        )
        (pin no_connect line (at 5.08 -36.83 0) (length 5.08) hide
          (name "RESERVED" (effects (font (size 1.27 1.27))))
          (number "AK24" (effects (font (size 1.27 1.27))))
        )
        (pin no_connect line (at 5.08 -38.1 0) (length 5.08) hide
          (name "RESERVED" (effects (font (size 1.27 1.27))))
          (number "AK25" (effects (font (size 1.27 1.27))))
        )
        (pin passive line (at 38.1 -40.64 180) (length 5.08) hide
          (name "GND" (effects (font (size 1.27 1.27))))
          (number "AK26" (effects (font (size 1.27 1.27))))
        )
        (pin passive line (at 38.1 -40.64 180) (length 5.08) hide
          (name "GND" (effects (font (size 1.27 1.27))))
          (number "AK7" (effects (font (size 1.27 1.27))))
        )
        (pin passive line (at 38.1 -40.64 180) (length 5.08) hide
          (name "GND" (effects (font (size 1.27 1.27))))
          (number "AK8" (effects (font (size 1.27 1.27))))
        )
        (pin passive line (at 38.1 -40.64 180) (length 5.08) hide
          (name "GND" (effects (font (size 1.27 1.27))))
          (number "AL11" (effects (font (size 1.27 1.27))))
        )
        (pin passive line (at 38.1 -40.64 180) (length 5.08) hide
          (name "GND" (effects (font (size 1.27 1.27))))
          (number "AL12" (effects (font (size 1.27 1.27))))
        )
        (pin passive line (at 38.1 -40.64 180) (length 5.08) hide
          (name "GND" (effects (font (size 1.27 1.27))))
          (number "AL14" (effects (font (size 1.27 1.27))))
        )
        (pin passive line (at 38.1 -40.64 180) (length 5.08) hide
          (name "GND" (effects (font (size 1.27 1.27))))
          (number "AL15" (effects (font (size 1.27 1.27))))
        )
        (pin passive line (at 38.1 -40.64 180) (length 5.08) hide
          (name "GND" (effects (font (size 1.27 1.27))))
          (number "AL17" (effects (font (size 1.27 1.27))))
        )
        (pin passive line (at 38.1 -40.64 180) (length 5.08) hide
          (name "GND" (effects (font (size 1.27 1.27))))
          (number "AL18" (effects (font (size 1.27 1.27))))
        )
        (pin passive line (at 38.1 -40.64 180) (length 5.08) hide
          (name "GND" (effects (font (size 1.27 1.27))))
          (number "AL2" (effects (font (size 1.27 1.27))))
        )
        (pin passive line (at 38.1 -40.64 180) (length 5.08) hide
          (name "GND" (effects (font (size 1.27 1.27))))
          (number "AL20" (effects (font (size 1.27 1.27))))
        )
        (pin passive line (at 38.1 -40.64 180) (length 5.08) hide
          (name "GND" (effects (font (size 1.27 1.27))))
          (number "AL21" (effects (font (size 1.27 1.27))))
        )
        (pin passive line (at 38.1 -40.64 180) (length 5.08) hide
          (name "GND" (effects (font (size 1.27 1.27))))
          (number "AL23" (effects (font (size 1.27 1.27))))
        )
        (pin passive line (at 38.1 -40.64 180) (length 5.08) hide
          (name "GND" (effects (font (size 1.27 1.27))))
          (number "AL24" (effects (font (size 1.27 1.27))))
        )
        (pin passive line (at 38.1 -40.64 180) (length 5.08) hide
          (name "GND" (effects (font (size 1.27 1.27))))
          (number "AL26" (effects (font (size 1.27 1.27))))
        )
        (pin passive line (at 38.1 -40.64 180) (length 5.08) hide
          (name "GND" (effects (font (size 1.27 1.27))))
          (number "AL29" (effects (font (size 1.27 1.27))))
        )
        (pin passive line (at 38.1 -40.64 180) (length 5.08) hide
          (name "GND" (effects (font (size 1.27 1.27))))
          (number "AL31" (effects (font (size 1.27 1.27))))
        )
        (pin passive line (at 38.1 -40.64 180) (length 5.08) hide
          (name "GND" (effects (font (size 1.27 1.27))))
          (number "AL5" (effects (font (size 1.27 1.27))))
        )
        (pin passive line (at 38.1 -40.64 180) (length 5.08) hide
          (name "GND" (effects (font (size 1.27 1.27))))
          (number "AL7" (effects (font (size 1.27 1.27))))
        )
        (pin passive line (at 38.1 -40.64 180) (length 5.08) hide
          (name "GND" (effects (font (size 1.27 1.27))))
          (number "AL8" (effects (font (size 1.27 1.27))))
        )
        (pin passive line (at 38.1 -40.64 180) (length 5.08) hide
          (name "GND" (effects (font (size 1.27 1.27))))
          (number "AL9" (effects (font (size 1.27 1.27))))
        )
        (pin passive line (at 38.1 -40.64 180) (length 5.08) hide
          (name "GND" (effects (font (size 1.27 1.27))))
          (number "AM26" (effects (font (size 1.27 1.27))))
        )
        (pin passive line (at 38.1 -40.64 180) (length 5.08) hide
          (name "GND" (effects (font (size 1.27 1.27))))
          (number "AM7" (effects (font (size 1.27 1.27))))
        )
        (pin passive line (at 38.1 -40.64 180) (length 5.08) hide
          (name "GND" (effects (font (size 1.27 1.27))))
          (number "B13" (effects (font (size 1.27 1.27))))
        )
        (pin passive line (at 38.1 -40.64 180) (length 5.08) hide
          (name "GND" (effects (font (size 1.27 1.27))))
          (number "B15" (effects (font (size 1.27 1.27))))
        )
        (pin passive line (at 38.1 -40.64 180) (length 5.08) hide
          (name "GND" (effects (font (size 1.27 1.27))))
          (number "B18" (effects (font (size 1.27 1.27))))
        )
        (pin passive line (at 38.1 -40.64 180) (length 5.08) hide
          (name "GND" (effects (font (size 1.27 1.27))))
          (number "B2" (effects (font (size 1.27 1.27))))
        )
        (pin passive line (at 38.1 -40.64 180) (length 5.08) hide
          (name "GND" (effects (font (size 1.27 1.27))))
          (number "B20" (effects (font (size 1.27 1.27))))
        )
        (pin passive line (at 38.1 -40.64 180) (length 5.08) hide
          (name "GND" (effects (font (size 1.27 1.27))))
          (number "B24" (effects (font (size 1.27 1.27))))
        )
        (pin passive line (at 38.1 -40.64 180) (length 5.08) hide
          (name "GND" (effects (font (size 1.27 1.27))))
          (number "B28" (effects (font (size 1.27 1.27))))
        )
        (pin passive line (at 38.1 -40.64 180) (length 5.08) hide
          (name "GND" (effects (font (size 1.27 1.27))))
          (number "B31" (effects (font (size 1.27 1.27))))
        )
        (pin passive line (at 38.1 -40.64 180) (length 5.08) hide
          (name "GND" (effects (font (size 1.27 1.27))))
          (number "B5" (effects (font (size 1.27 1.27))))
        )
        (pin passive line (at 38.1 -40.64 180) (length 5.08) hide
          (name "GND" (effects (font (size 1.27 1.27))))
          (number "B9" (effects (font (size 1.27 1.27))))
        )
        (pin passive line (at 38.1 -40.64 180) (length 5.08) hide
          (name "GND" (effects (font (size 1.27 1.27))))
          (number "E13" (effects (font (size 1.27 1.27))))
        )
        (pin passive line (at 38.1 -40.64 180) (length 5.08) hide
          (name "GND" (effects (font (size 1.27 1.27))))
          (number "E15" (effects (font (size 1.27 1.27))))
        )
        (pin passive line (at 38.1 -40.64 180) (length 5.08) hide
          (name "GND" (effects (font (size 1.27 1.27))))
          (number "E18" (effects (font (size 1.27 1.27))))
        )
        (pin passive line (at 38.1 -40.64 180) (length 5.08) hide
          (name "GND" (effects (font (size 1.27 1.27))))
          (number "E2" (effects (font (size 1.27 1.27))))
        )
        (pin passive line (at 38.1 -40.64 180) (length 5.08) hide
          (name "GND" (effects (font (size 1.27 1.27))))
          (number "E20" (effects (font (size 1.27 1.27))))
        )
        (pin passive line (at 38.1 -40.64 180) (length 5.08) hide
          (name "GND" (effects (font (size 1.27 1.27))))
          (number "E24" (effects (font (size 1.27 1.27))))
        )
        (pin no_connect line (at 33.02 -29.21 180) (length 5.08) hide
          (name "NC" (effects (font (size 1.27 1.27))))
          (number "E26" (effects (font (size 1.27 1.27))))
        )
        (pin passive line (at 38.1 -40.64 180) (length 5.08) hide
          (name "GND" (effects (font (size 1.27 1.27))))
          (number "E28" (effects (font (size 1.27 1.27))))
        )
        (pin passive line (at 38.1 -40.64 180) (length 5.08) hide
          (name "GND" (effects (font (size 1.27 1.27))))
          (number "E31" (effects (font (size 1.27 1.27))))
        )
        (pin passive line (at 38.1 -40.64 180) (length 5.08) hide
          (name "GND" (effects (font (size 1.27 1.27))))
          (number "E5" (effects (font (size 1.27 1.27))))
        )
        (pin no_connect line (at 33.02 -30.48 180) (length 5.08) hide
          (name "NC" (effects (font (size 1.27 1.27))))
          (number "E7" (effects (font (size 1.27 1.27))))
        )
        (pin passive line (at 38.1 -40.64 180) (length 5.08) hide
          (name "GND" (effects (font (size 1.27 1.27))))
          (number "E9" (effects (font (size 1.27 1.27))))
        )
        (pin no_connect line (at 33.02 -31.75 180) (length 5.08) hide
          (name "NC" (effects (font (size 1.27 1.27))))
          (number "G10" (effects (font (size 1.27 1.27))))
        )
        (pin no_connect line (at 33.02 -33.02 180) (length 5.08) hide
          (name "NC" (effects (font (size 1.27 1.27))))
          (number "G11" (effects (font (size 1.27 1.27))))
        )
        (pin no_connect line (at 33.02 -34.29 180) (length 5.08) hide
          (name "NC" (effects (font (size 1.27 1.27))))
          (number "G14" (effects (font (size 1.27 1.27))))
        )
        (pin no_connect line (at 5.08 -21.59 0) (length 5.08) hide
          (name "NC" (effects (font (size 1.27 1.27))))
          (number "G15" (effects (font (size 1.27 1.27))))
        )
        (pin no_connect line (at 5.08 -22.86 0) (length 5.08) hide
          (name "NC" (effects (font (size 1.27 1.27))))
          (number "G16" (effects (font (size 1.27 1.27))))
        )
        (pin no_connect line (at 5.08 -24.13 0) (length 5.08) hide
          (name "NC" (effects (font (size 1.27 1.27))))
          (number "G17" (effects (font (size 1.27 1.27))))
        )
        (pin no_connect line (at 5.08 -25.4 0) (length 5.08) hide
          (name "NC" (effects (font (size 1.27 1.27))))
          (number "G18" (effects (font (size 1.27 1.27))))
        )
        (pin no_connect line (at 5.08 -26.67 0) (length 5.08) hide
          (name "NC" (effects (font (size 1.27 1.27))))
          (number "G19" (effects (font (size 1.27 1.27))))
        )
        (pin no_connect line (at 5.08 -27.94 0) (length 5.08) hide
          (name "NC" (effects (font (size 1.27 1.27))))
          (number "G22" (effects (font (size 1.27 1.27))))
        )
        (pin no_connect line (at 5.08 -29.21 0) (length 5.08) hide
          (name "NC" (effects (font (size 1.27 1.27))))
          (number "G23" (effects (font (size 1.27 1.27))))
        )
        (pin no_connect line (at 5.08 -30.48 0) (length 5.08) hide
          (name "NC" (effects (font (size 1.27 1.27))))
          (number "G24" (effects (font (size 1.27 1.27))))
        )
        (pin no_connect line (at 5.08 -31.75 0) (length 5.08) hide
          (name "NC" (effects (font (size 1.27 1.27))))
          (number "G9" (effects (font (size 1.27 1.27))))
        )
        (pin no_connect line (at 5.08 -16.51 0) (length 5.08) hide
          (name "NC" (effects (font (size 1.27 1.27))))
          (number "H29" (effects (font (size 1.27 1.27))))
        )
        (pin no_connect line (at 5.08 -17.78 0) (length 5.08) hide
          (name "NC" (effects (font (size 1.27 1.27))))
          (number "H4" (effects (font (size 1.27 1.27))))
        )
        (pin passive line (at 38.1 -40.64 180) (length 5.08) hide
          (name "GND" (effects (font (size 1.27 1.27))))
          (number "J2" (effects (font (size 1.27 1.27))))
        )
        (pin passive line (at 38.1 -40.64 180) (length 5.08) hide
          (name "GND" (effects (font (size 1.27 1.27))))
          (number "J28" (effects (font (size 1.27 1.27))))
        )
        (pin passive line (at 38.1 -40.64 180) (length 5.08) hide
          (name "GND" (effects (font (size 1.27 1.27))))
          (number "J31" (effects (font (size 1.27 1.27))))
        )
        (pin passive line (at 38.1 -40.64 180) (length 5.08) hide
          (name "GND" (effects (font (size 1.27 1.27))))
          (number "J5" (effects (font (size 1.27 1.27))))
        )
        (pin passive line (at 38.1 -40.64 180) (length 5.08) hide
          (name "GND" (effects (font (size 1.27 1.27))))
          (number "K10" (effects (font (size 1.27 1.27))))
        )
        (pin passive line (at 38.1 -40.64 180) (length 5.08) hide
          (name "GND" (effects (font (size 1.27 1.27))))
          (number "K11" (effects (font (size 1.27 1.27))))
        )
        (pin passive line (at 0 -8.89 0) (length 5.08) hide
          (name "VCCAUX" (effects (font (size 1.27 1.27))))
          (number "K13" (effects (font (size 1.27 1.27))))
        )
        (pin passive line (at 0 -8.89 0) (length 5.08) hide
          (name "VCCAUX" (effects (font (size 1.27 1.27))))
          (number "K20" (effects (font (size 1.27 1.27))))
        )
        (pin passive line (at 38.1 -40.64 180) (length 5.08) hide
          (name "GND" (effects (font (size 1.27 1.27))))
          (number "K22" (effects (font (size 1.27 1.27))))
        )
        (pin passive line (at 38.1 -40.64 180) (length 5.08) hide
          (name "GND" (effects (font (size 1.27 1.27))))
          (number "K23" (effects (font (size 1.27 1.27))))
        )
        (pin passive line (at 38.1 -40.64 180) (length 5.08) hide
          (name "GND" (effects (font (size 1.27 1.27))))
          (number "L10" (effects (font (size 1.27 1.27))))
        )
        (pin passive line (at 38.1 -40.64 180) (length 5.08) hide
          (name "GND" (effects (font (size 1.27 1.27))))
          (number "L11" (effects (font (size 1.27 1.27))))
        )
        (pin passive line (at 38.1 -40.64 180) (length 5.08) hide
          (name "GND" (effects (font (size 1.27 1.27))))
          (number "L12" (effects (font (size 1.27 1.27))))
        )
        (pin passive line (at 38.1 -40.64 180) (length 5.08) hide
          (name "GND" (effects (font (size 1.27 1.27))))
          (number "L13" (effects (font (size 1.27 1.27))))
        )
        (pin passive line (at 38.1 -40.64 180) (length 5.08) hide
          (name "GND" (effects (font (size 1.27 1.27))))
          (number "L14" (effects (font (size 1.27 1.27))))
        )
        (pin passive line (at 38.1 -40.64 180) (length 5.08) hide
          (name "GND" (effects (font (size 1.27 1.27))))
          (number "L15" (effects (font (size 1.27 1.27))))
        )
        (pin passive line (at 38.1 -40.64 180) (length 5.08) hide
          (name "GND" (effects (font (size 1.27 1.27))))
          (number "L16" (effects (font (size 1.27 1.27))))
        )
        (pin passive line (at 38.1 -40.64 180) (length 5.08) hide
          (name "GND" (effects (font (size 1.27 1.27))))
          (number "L17" (effects (font (size 1.27 1.27))))
        )
        (pin passive line (at 38.1 -40.64 180) (length 5.08) hide
          (name "GND" (effects (font (size 1.27 1.27))))
          (number "L18" (effects (font (size 1.27 1.27))))
        )
        (pin passive line (at 38.1 -40.64 180) (length 5.08) hide
          (name "GND" (effects (font (size 1.27 1.27))))
          (number "L19" (effects (font (size 1.27 1.27))))
        )
        (pin passive line (at 38.1 -40.64 180) (length 5.08) hide
          (name "GND" (effects (font (size 1.27 1.27))))
          (number "L20" (effects (font (size 1.27 1.27))))
        )
        (pin passive line (at 38.1 -40.64 180) (length 5.08) hide
          (name "GND" (effects (font (size 1.27 1.27))))
          (number "L21" (effects (font (size 1.27 1.27))))
        )
        (pin passive line (at 38.1 -40.64 180) (length 5.08) hide
          (name "GND" (effects (font (size 1.27 1.27))))
          (number "L22" (effects (font (size 1.27 1.27))))
        )
        (pin passive line (at 38.1 -40.64 180) (length 5.08) hide
          (name "GND" (effects (font (size 1.27 1.27))))
          (number "L23" (effects (font (size 1.27 1.27))))
        )
        (pin no_connect line (at 5.08 -19.05 0) (length 5.08) hide
          (name "NC" (effects (font (size 1.27 1.27))))
          (number "L28" (effects (font (size 1.27 1.27))))
        )
        (pin no_connect line (at 5.08 -20.32 0) (length 5.08) hide
          (name "NC" (effects (font (size 1.27 1.27))))
          (number "L5" (effects (font (size 1.27 1.27))))
        )
        (pin passive line (at 38.1 -40.64 180) (length 5.08) hide
          (name "GND" (effects (font (size 1.27 1.27))))
          (number "M11" (effects (font (size 1.27 1.27))))
        )
        (pin passive line (at 0 0 0) (length 5.08) hide
          (name "VCC" (effects (font (size 1.27 1.27))))
          (number "M12" (effects (font (size 1.27 1.27))))
        )
        (pin passive line (at 0 0 0) (length 5.08) hide
          (name "VCC" (effects (font (size 1.27 1.27))))
          (number "M13" (effects (font (size 1.27 1.27))))
        )
        (pin passive line (at 0 0 0) (length 5.08) hide
          (name "VCC" (effects (font (size 1.27 1.27))))
          (number "M14" (effects (font (size 1.27 1.27))))
        )
        (pin passive line (at 0 0 0) (length 5.08) hide
          (name "VCC" (effects (font (size 1.27 1.27))))
          (number "M15" (effects (font (size 1.27 1.27))))
        )
        (pin passive line (at 0 0 0) (length 5.08) hide
          (name "VCC" (effects (font (size 1.27 1.27))))
          (number "M16" (effects (font (size 1.27 1.27))))
        )
        (pin passive line (at 0 0 0) (length 5.08) hide
          (name "VCC" (effects (font (size 1.27 1.27))))
          (number "M17" (effects (font (size 1.27 1.27))))
        )
        (pin passive line (at 0 0 0) (length 5.08) hide
          (name "VCC" (effects (font (size 1.27 1.27))))
          (number "M18" (effects (font (size 1.27 1.27))))
        )
        (pin passive line (at 0 0 0) (length 5.08) hide
          (name "VCC" (effects (font (size 1.27 1.27))))
          (number "M19" (effects (font (size 1.27 1.27))))
        )
        (pin passive line (at 0 0 0) (length 5.08) hide
          (name "VCC" (effects (font (size 1.27 1.27))))
          (number "M20" (effects (font (size 1.27 1.27))))
        )
        (pin passive line (at 0 0 0) (length 5.08) hide
          (name "VCC" (effects (font (size 1.27 1.27))))
          (number "M21" (effects (font (size 1.27 1.27))))
        )
        (pin passive line (at 38.1 -40.64 180) (length 5.08) hide
          (name "GND" (effects (font (size 1.27 1.27))))
          (number "M22" (effects (font (size 1.27 1.27))))
        )
        (pin passive line (at 0 -8.89 0) (length 5.08) hide
          (name "VCCAUX" (effects (font (size 1.27 1.27))))
          (number "N10" (effects (font (size 1.27 1.27))))
        )
        (pin passive line (at 38.1 -40.64 180) (length 5.08) hide
          (name "GND" (effects (font (size 1.27 1.27))))
          (number "N11" (effects (font (size 1.27 1.27))))
        )
        (pin passive line (at 0 0 0) (length 5.08) hide
          (name "VCC" (effects (font (size 1.27 1.27))))
          (number "N12" (effects (font (size 1.27 1.27))))
        )
        (pin passive line (at 38.1 -40.64 180) (length 5.08) hide
          (name "GND" (effects (font (size 1.27 1.27))))
          (number "N13" (effects (font (size 1.27 1.27))))
        )
        (pin passive line (at 38.1 -40.64 180) (length 5.08) hide
          (name "GND" (effects (font (size 1.27 1.27))))
          (number "N14" (effects (font (size 1.27 1.27))))
        )
        (pin passive line (at 38.1 -40.64 180) (length 5.08) hide
          (name "GND" (effects (font (size 1.27 1.27))))
          (number "N15" (effects (font (size 1.27 1.27))))
        )
        (pin passive line (at 38.1 -40.64 180) (length 5.08) hide
          (name "GND" (effects (font (size 1.27 1.27))))
          (number "N16" (effects (font (size 1.27 1.27))))
        )
        (pin passive line (at 38.1 -40.64 180) (length 5.08) hide
          (name "GND" (effects (font (size 1.27 1.27))))
          (number "N17" (effects (font (size 1.27 1.27))))
        )
        (pin passive line (at 38.1 -40.64 180) (length 5.08) hide
          (name "GND" (effects (font (size 1.27 1.27))))
          (number "N18" (effects (font (size 1.27 1.27))))
        )
        (pin passive line (at 38.1 -40.64 180) (length 5.08) hide
          (name "GND" (effects (font (size 1.27 1.27))))
          (number "N19" (effects (font (size 1.27 1.27))))
        )
        (pin passive line (at 38.1 -40.64 180) (length 5.08) hide
          (name "GND" (effects (font (size 1.27 1.27))))
          (number "N2" (effects (font (size 1.27 1.27))))
        )
        (pin passive line (at 38.1 -40.64 180) (length 5.08) hide
          (name "GND" (effects (font (size 1.27 1.27))))
          (number "N20" (effects (font (size 1.27 1.27))))
        )
        (pin passive line (at 0 0 0) (length 5.08) hide
          (name "VCC" (effects (font (size 1.27 1.27))))
          (number "N21" (effects (font (size 1.27 1.27))))
        )
        (pin passive line (at 38.1 -40.64 180) (length 5.08) hide
          (name "GND" (effects (font (size 1.27 1.27))))
          (number "N22" (effects (font (size 1.27 1.27))))
        )
        (pin passive line (at 0 -8.89 0) (length 5.08) hide
          (name "VCCAUX" (effects (font (size 1.27 1.27))))
          (number "N23" (effects (font (size 1.27 1.27))))
        )
        (pin passive line (at 38.1 -40.64 180) (length 5.08) hide
          (name "GND" (effects (font (size 1.27 1.27))))
          (number "N28" (effects (font (size 1.27 1.27))))
        )
        (pin passive line (at 38.1 -40.64 180) (length 5.08) hide
          (name "GND" (effects (font (size 1.27 1.27))))
          (number "N31" (effects (font (size 1.27 1.27))))
        )
        (pin passive line (at 38.1 -40.64 180) (length 5.08) hide
          (name "GND" (effects (font (size 1.27 1.27))))
          (number "N5" (effects (font (size 1.27 1.27))))
        )
        (pin passive line (at 38.1 -40.64 180) (length 5.08) hide
          (name "GND" (effects (font (size 1.27 1.27))))
          (number "P11" (effects (font (size 1.27 1.27))))
        )
        (pin passive line (at 0 0 0) (length 5.08) hide
          (name "VCC" (effects (font (size 1.27 1.27))))
          (number "P12" (effects (font (size 1.27 1.27))))
        )
        (pin passive line (at 38.1 -40.64 180) (length 5.08) hide
          (name "GND" (effects (font (size 1.27 1.27))))
          (number "P13" (effects (font (size 1.27 1.27))))
        )
        (pin passive line (at 38.1 -40.64 180) (length 5.08) hide
          (name "GND" (effects (font (size 1.27 1.27))))
          (number "P14" (effects (font (size 1.27 1.27))))
        )
        (pin passive line (at 38.1 -40.64 180) (length 5.08) hide
          (name "GND" (effects (font (size 1.27 1.27))))
          (number "P15" (effects (font (size 1.27 1.27))))
        )
        (pin passive line (at 38.1 -40.64 180) (length 5.08) hide
          (name "GND" (effects (font (size 1.27 1.27))))
          (number "P16" (effects (font (size 1.27 1.27))))
        )
        (pin passive line (at 38.1 -40.64 180) (length 5.08) hide
          (name "GND" (effects (font (size 1.27 1.27))))
          (number "P17" (effects (font (size 1.27 1.27))))
        )
        (pin passive line (at 38.1 -40.64 180) (length 5.08) hide
          (name "GND" (effects (font (size 1.27 1.27))))
          (number "P18" (effects (font (size 1.27 1.27))))
        )
        (pin passive line (at 38.1 -40.64 180) (length 5.08) hide
          (name "GND" (effects (font (size 1.27 1.27))))
          (number "P19" (effects (font (size 1.27 1.27))))
        )
        (pin passive line (at 38.1 -40.64 180) (length 5.08) hide
          (name "GND" (effects (font (size 1.27 1.27))))
          (number "P20" (effects (font (size 1.27 1.27))))
        )
        (pin passive line (at 0 0 0) (length 5.08) hide
          (name "VCC" (effects (font (size 1.27 1.27))))
          (number "P21" (effects (font (size 1.27 1.27))))
        )
        (pin passive line (at 38.1 -40.64 180) (length 5.08) hide
          (name "GND" (effects (font (size 1.27 1.27))))
          (number "P22" (effects (font (size 1.27 1.27))))
        )
        (pin passive line (at 38.1 -40.64 180) (length 5.08) hide
          (name "GND" (effects (font (size 1.27 1.27))))
          (number "R11" (effects (font (size 1.27 1.27))))
        )
        (pin passive line (at 0 0 0) (length 5.08) hide
          (name "VCC" (effects (font (size 1.27 1.27))))
          (number "R12" (effects (font (size 1.27 1.27))))
        )
        (pin passive line (at 38.1 -40.64 180) (length 5.08) hide
          (name "GND" (effects (font (size 1.27 1.27))))
          (number "R13" (effects (font (size 1.27 1.27))))
        )
        (pin passive line (at 38.1 -40.64 180) (length 5.08) hide
          (name "GND" (effects (font (size 1.27 1.27))))
          (number "R14" (effects (font (size 1.27 1.27))))
        )
        (pin passive line (at 38.1 -40.64 180) (length 5.08) hide
          (name "GND" (effects (font (size 1.27 1.27))))
          (number "R15" (effects (font (size 1.27 1.27))))
        )
        (pin passive line (at 38.1 -40.64 180) (length 5.08) hide
          (name "GND" (effects (font (size 1.27 1.27))))
          (number "R16" (effects (font (size 1.27 1.27))))
        )
        (pin passive line (at 38.1 -40.64 180) (length 5.08) hide
          (name "GND" (effects (font (size 1.27 1.27))))
          (number "R17" (effects (font (size 1.27 1.27))))
        )
        (pin passive line (at 38.1 -40.64 180) (length 5.08) hide
          (name "GND" (effects (font (size 1.27 1.27))))
          (number "R18" (effects (font (size 1.27 1.27))))
        )
        (pin passive line (at 38.1 -40.64 180) (length 5.08) hide
          (name "GND" (effects (font (size 1.27 1.27))))
          (number "R19" (effects (font (size 1.27 1.27))))
        )
        (pin passive line (at 38.1 -40.64 180) (length 5.08) hide
          (name "GND" (effects (font (size 1.27 1.27))))
          (number "R2" (effects (font (size 1.27 1.27))))
        )
        (pin passive line (at 38.1 -40.64 180) (length 5.08) hide
          (name "GND" (effects (font (size 1.27 1.27))))
          (number "R20" (effects (font (size 1.27 1.27))))
        )
        (pin passive line (at 0 0 0) (length 5.08) hide
          (name "VCC" (effects (font (size 1.27 1.27))))
          (number "R21" (effects (font (size 1.27 1.27))))
        )
        (pin passive line (at 38.1 -40.64 180) (length 5.08) hide
          (name "GND" (effects (font (size 1.27 1.27))))
          (number "R22" (effects (font (size 1.27 1.27))))
        )
        (pin passive line (at 38.1 -40.64 180) (length 5.08) hide
          (name "GND" (effects (font (size 1.27 1.27))))
          (number "R28" (effects (font (size 1.27 1.27))))
        )
        (pin passive line (at 38.1 -40.64 180) (length 5.08) hide
          (name "GND" (effects (font (size 1.27 1.27))))
          (number "R31" (effects (font (size 1.27 1.27))))
        )
        (pin passive line (at 38.1 -40.64 180) (length 5.08) hide
          (name "GND" (effects (font (size 1.27 1.27))))
          (number "R5" (effects (font (size 1.27 1.27))))
        )
        (pin passive line (at 38.1 -40.64 180) (length 5.08) hide
          (name "GND" (effects (font (size 1.27 1.27))))
          (number "T11" (effects (font (size 1.27 1.27))))
        )
        (pin passive line (at 0 0 0) (length 5.08) hide
          (name "VCC" (effects (font (size 1.27 1.27))))
          (number "T12" (effects (font (size 1.27 1.27))))
        )
        (pin passive line (at 38.1 -40.64 180) (length 5.08) hide
          (name "GND" (effects (font (size 1.27 1.27))))
          (number "T13" (effects (font (size 1.27 1.27))))
        )
        (pin passive line (at 38.1 -40.64 180) (length 5.08) hide
          (name "GND" (effects (font (size 1.27 1.27))))
          (number "T14" (effects (font (size 1.27 1.27))))
        )
        (pin passive line (at 38.1 -40.64 180) (length 5.08) hide
          (name "GND" (effects (font (size 1.27 1.27))))
          (number "T15" (effects (font (size 1.27 1.27))))
        )
        (pin passive line (at 38.1 -40.64 180) (length 5.08) hide
          (name "GND" (effects (font (size 1.27 1.27))))
          (number "T16" (effects (font (size 1.27 1.27))))
        )
        (pin passive line (at 38.1 -40.64 180) (length 5.08) hide
          (name "GND" (effects (font (size 1.27 1.27))))
          (number "T17" (effects (font (size 1.27 1.27))))
        )
        (pin passive line (at 38.1 -40.64 180) (length 5.08) hide
          (name "GND" (effects (font (size 1.27 1.27))))
          (number "T18" (effects (font (size 1.27 1.27))))
        )
        (pin passive line (at 38.1 -40.64 180) (length 5.08) hide
          (name "GND" (effects (font (size 1.27 1.27))))
          (number "T19" (effects (font (size 1.27 1.27))))
        )
        (pin passive line (at 38.1 -40.64 180) (length 5.08) hide
          (name "GND" (effects (font (size 1.27 1.27))))
          (number "T20" (effects (font (size 1.27 1.27))))
        )
        (pin passive line (at 0 0 0) (length 5.08) hide
          (name "VCC" (effects (font (size 1.27 1.27))))
          (number "T21" (effects (font (size 1.27 1.27))))
        )
        (pin passive line (at 38.1 -40.64 180) (length 5.08) hide
          (name "GND" (effects (font (size 1.27 1.27))))
          (number "T22" (effects (font (size 1.27 1.27))))
        )
        (pin passive line (at 38.1 -40.64 180) (length 5.08) hide
          (name "GND" (effects (font (size 1.27 1.27))))
          (number "U11" (effects (font (size 1.27 1.27))))
        )
        (pin passive line (at 0 0 0) (length 5.08) hide
          (name "VCC" (effects (font (size 1.27 1.27))))
          (number "U12" (effects (font (size 1.27 1.27))))
        )
        (pin passive line (at 38.1 -40.64 180) (length 5.08) hide
          (name "GND" (effects (font (size 1.27 1.27))))
          (number "U13" (effects (font (size 1.27 1.27))))
        )
        (pin passive line (at 38.1 -40.64 180) (length 5.08) hide
          (name "GND" (effects (font (size 1.27 1.27))))
          (number "U14" (effects (font (size 1.27 1.27))))
        )
        (pin passive line (at 38.1 -40.64 180) (length 5.08) hide
          (name "GND" (effects (font (size 1.27 1.27))))
          (number "U15" (effects (font (size 1.27 1.27))))
        )
        (pin passive line (at 38.1 -40.64 180) (length 5.08) hide
          (name "GND" (effects (font (size 1.27 1.27))))
          (number "U16" (effects (font (size 1.27 1.27))))
        )
        (pin passive line (at 38.1 -40.64 180) (length 5.08) hide
          (name "GND" (effects (font (size 1.27 1.27))))
          (number "U17" (effects (font (size 1.27 1.27))))
        )
        (pin passive line (at 38.1 -40.64 180) (length 5.08) hide
          (name "GND" (effects (font (size 1.27 1.27))))
          (number "U18" (effects (font (size 1.27 1.27))))
        )
        (pin passive line (at 38.1 -40.64 180) (length 5.08) hide
          (name "GND" (effects (font (size 1.27 1.27))))
          (number "U19" (effects (font (size 1.27 1.27))))
        )
        (pin passive line (at 38.1 -40.64 180) (length 5.08) hide
          (name "GND" (effects (font (size 1.27 1.27))))
          (number "U20" (effects (font (size 1.27 1.27))))
        )
        (pin passive line (at 0 0 0) (length 5.08) hide
          (name "VCC" (effects (font (size 1.27 1.27))))
          (number "U21" (effects (font (size 1.27 1.27))))
        )
        (pin passive line (at 38.1 -40.64 180) (length 5.08) hide
          (name "GND" (effects (font (size 1.27 1.27))))
          (number "U22" (effects (font (size 1.27 1.27))))
        )
        (pin passive line (at 38.1 -40.64 180) (length 5.08) hide
          (name "GND" (effects (font (size 1.27 1.27))))
          (number "V11" (effects (font (size 1.27 1.27))))
        )
        (pin passive line (at 0 0 0) (length 5.08) hide
          (name "VCC" (effects (font (size 1.27 1.27))))
          (number "V12" (effects (font (size 1.27 1.27))))
        )
        (pin passive line (at 38.1 -40.64 180) (length 5.08) hide
          (name "GND" (effects (font (size 1.27 1.27))))
          (number "V13" (effects (font (size 1.27 1.27))))
        )
        (pin passive line (at 38.1 -40.64 180) (length 5.08) hide
          (name "GND" (effects (font (size 1.27 1.27))))
          (number "V14" (effects (font (size 1.27 1.27))))
        )
        (pin passive line (at 38.1 -40.64 180) (length 5.08) hide
          (name "GND" (effects (font (size 1.27 1.27))))
          (number "V15" (effects (font (size 1.27 1.27))))
        )
        (pin passive line (at 38.1 -40.64 180) (length 5.08) hide
          (name "GND" (effects (font (size 1.27 1.27))))
          (number "V16" (effects (font (size 1.27 1.27))))
        )
        (pin passive line (at 38.1 -40.64 180) (length 5.08) hide
          (name "GND" (effects (font (size 1.27 1.27))))
          (number "V17" (effects (font (size 1.27 1.27))))
        )
        (pin passive line (at 38.1 -40.64 180) (length 5.08) hide
          (name "GND" (effects (font (size 1.27 1.27))))
          (number "V18" (effects (font (size 1.27 1.27))))
        )
        (pin passive line (at 38.1 -40.64 180) (length 5.08) hide
          (name "GND" (effects (font (size 1.27 1.27))))
          (number "V19" (effects (font (size 1.27 1.27))))
        )
        (pin passive line (at 38.1 -40.64 180) (length 5.08) hide
          (name "GND" (effects (font (size 1.27 1.27))))
          (number "V2" (effects (font (size 1.27 1.27))))
        )
        (pin passive line (at 38.1 -40.64 180) (length 5.08) hide
          (name "GND" (effects (font (size 1.27 1.27))))
          (number "V20" (effects (font (size 1.27 1.27))))
        )
        (pin passive line (at 0 0 0) (length 5.08) hide
          (name "VCC" (effects (font (size 1.27 1.27))))
          (number "V21" (effects (font (size 1.27 1.27))))
        )
        (pin passive line (at 38.1 -40.64 180) (length 5.08) hide
          (name "GND" (effects (font (size 1.27 1.27))))
          (number "V22" (effects (font (size 1.27 1.27))))
        )
        (pin passive line (at 38.1 -40.64 180) (length 5.08) hide
          (name "GND" (effects (font (size 1.27 1.27))))
          (number "V28" (effects (font (size 1.27 1.27))))
        )
        (pin no_connect line (at 33.02 -35.56 180) (length 5.08) hide
          (name "NC" (effects (font (size 1.27 1.27))))
          (number "V3" (effects (font (size 1.27 1.27))))
        )
        (pin no_connect line (at 33.02 -36.83 180) (length 5.08) hide
          (name "NC" (effects (font (size 1.27 1.27))))
          (number "V30" (effects (font (size 1.27 1.27))))
        )
        (pin passive line (at 38.1 -40.64 180) (length 5.08) hide
          (name "GND" (effects (font (size 1.27 1.27))))
          (number "V31" (effects (font (size 1.27 1.27))))
        )
        (pin passive line (at 38.1 -40.64 180) (length 5.08) hide
          (name "GND" (effects (font (size 1.27 1.27))))
          (number "V5" (effects (font (size 1.27 1.27))))
        )
        (pin passive line (at 38.1 -40.64 180) (length 5.08) hide
          (name "GND" (effects (font (size 1.27 1.27))))
          (number "W11" (effects (font (size 1.27 1.27))))
        )
        (pin passive line (at 0 0 0) (length 5.08) hide
          (name "VCC" (effects (font (size 1.27 1.27))))
          (number "W12" (effects (font (size 1.27 1.27))))
        )
        (pin passive line (at 38.1 -40.64 180) (length 5.08) hide
          (name "GND" (effects (font (size 1.27 1.27))))
          (number "W13" (effects (font (size 1.27 1.27))))
        )
        (pin passive line (at 38.1 -40.64 180) (length 5.08) hide
          (name "GND" (effects (font (size 1.27 1.27))))
          (number "W14" (effects (font (size 1.27 1.27))))
        )
        (pin passive line (at 38.1 -40.64 180) (length 5.08) hide
          (name "GND" (effects (font (size 1.27 1.27))))
          (number "W15" (effects (font (size 1.27 1.27))))
        )
        (pin passive line (at 38.1 -40.64 180) (length 5.08) hide
          (name "GND" (effects (font (size 1.27 1.27))))
          (number "W16" (effects (font (size 1.27 1.27))))
        )
        (pin passive line (at 38.1 -40.64 180) (length 5.08) hide
          (name "GND" (effects (font (size 1.27 1.27))))
          (number "W17" (effects (font (size 1.27 1.27))))
        )
        (pin passive line (at 38.1 -40.64 180) (length 5.08) hide
          (name "GND" (effects (font (size 1.27 1.27))))
          (number "W18" (effects (font (size 1.27 1.27))))
        )
        (pin passive line (at 38.1 -40.64 180) (length 5.08) hide
          (name "GND" (effects (font (size 1.27 1.27))))
          (number "W19" (effects (font (size 1.27 1.27))))
        )
        (pin passive line (at 38.1 -40.64 180) (length 5.08) hide
          (name "GND" (effects (font (size 1.27 1.27))))
          (number "W20" (effects (font (size 1.27 1.27))))
        )
        (pin passive line (at 0 0 0) (length 5.08) hide
          (name "VCC" (effects (font (size 1.27 1.27))))
          (number "W21" (effects (font (size 1.27 1.27))))
        )
        (pin passive line (at 38.1 -40.64 180) (length 5.08) hide
          (name "GND" (effects (font (size 1.27 1.27))))
          (number "W22" (effects (font (size 1.27 1.27))))
        )
        (pin no_connect line (at 33.02 -38.1 180) (length 5.08) hide
          (name "NC" (effects (font (size 1.27 1.27))))
          (number "W27" (effects (font (size 1.27 1.27))))
        )
        (pin no_connect line (at 5.08 -33.02 0) (length 5.08) hide
          (name "NC" (effects (font (size 1.27 1.27))))
          (number "W6" (effects (font (size 1.27 1.27))))
        )
        (pin passive line (at 0 -8.89 0) (length 5.08) hide
          (name "VCCAUX" (effects (font (size 1.27 1.27))))
          (number "Y10" (effects (font (size 1.27 1.27))))
        )
        (pin passive line (at 38.1 -40.64 180) (length 5.08) hide
          (name "GND" (effects (font (size 1.27 1.27))))
          (number "Y11" (effects (font (size 1.27 1.27))))
        )
        (pin passive line (at 0 0 0) (length 5.08) hide
          (name "VCC" (effects (font (size 1.27 1.27))))
          (number "Y12" (effects (font (size 1.27 1.27))))
        )
        (pin passive line (at 38.1 -40.64 180) (length 5.08) hide
          (name "GND" (effects (font (size 1.27 1.27))))
          (number "Y13" (effects (font (size 1.27 1.27))))
        )
        (pin passive line (at 38.1 -40.64 180) (length 5.08) hide
          (name "GND" (effects (font (size 1.27 1.27))))
          (number "Y14" (effects (font (size 1.27 1.27))))
        )
        (pin passive line (at 38.1 -40.64 180) (length 5.08) hide
          (name "GND" (effects (font (size 1.27 1.27))))
          (number "Y15" (effects (font (size 1.27 1.27))))
        )
        (pin passive line (at 38.1 -40.64 180) (length 5.08) hide
          (name "GND" (effects (font (size 1.27 1.27))))
          (number "Y16" (effects (font (size 1.27 1.27))))
        )
        (pin passive line (at 38.1 -40.64 180) (length 5.08) hide
          (name "GND" (effects (font (size 1.27 1.27))))
          (number "Y17" (effects (font (size 1.27 1.27))))
        )
        (pin passive line (at 38.1 -40.64 180) (length 5.08) hide
          (name "GND" (effects (font (size 1.27 1.27))))
          (number "Y18" (effects (font (size 1.27 1.27))))
        )
        (pin passive line (at 38.1 -40.64 180) (length 5.08) hide
          (name "GND" (effects (font (size 1.27 1.27))))
          (number "Y19" (effects (font (size 1.27 1.27))))
        )
        (pin passive line (at 38.1 -40.64 180) (length 5.08) hide
          (name "GND" (effects (font (size 1.27 1.27))))
          (number "Y2" (effects (font (size 1.27 1.27))))
        )
        (pin passive line (at 38.1 -40.64 180) (length 5.08) hide
          (name "GND" (effects (font (size 1.27 1.27))))
          (number "Y20" (effects (font (size 1.27 1.27))))
        )
        (pin passive line (at 0 0 0) (length 5.08) hide
          (name "VCC" (effects (font (size 1.27 1.27))))
          (number "Y21" (effects (font (size 1.27 1.27))))
        )
        (pin passive line (at 38.1 -40.64 180) (length 5.08) hide
          (name "GND" (effects (font (size 1.27 1.27))))
          (number "Y22" (effects (font (size 1.27 1.27))))
        )
        (pin passive line (at 0 -8.89 0) (length 5.08) hide
          (name "VCCAUX" (effects (font (size 1.27 1.27))))
          (number "Y23" (effects (font (size 1.27 1.27))))
        )
        (pin passive line (at 38.1 -40.64 180) (length 5.08) hide
          (name "GND" (effects (font (size 1.27 1.27))))
          (number "Y31" (effects (font (size 1.27 1.27))))
        )
      )
      (symbol "ECP5_LFE5UM5G-85_2_1"
        (rectangle (start 5.08 2.54) (end 22.86 -142.24)
          (stroke (width 0.254) (type default))
          (fill (type background))
        )
        (pin bidirectional line (at 0 -73.66 0) (length 5.08)
          (name "PT31B" (effects (font (size 1.27 1.27))))
          (number "A10" (effects (font (size 1.27 1.27))))
        )
        (pin bidirectional line (at 0 -60.96 0) (length 5.08)
          (name "PT38B" (effects (font (size 1.27 1.27))))
          (number "A11" (effects (font (size 1.27 1.27))))
        )
        (pin bidirectional line (at 0 -50.8 0) (length 5.08)
          (name "PT42B" (effects (font (size 1.27 1.27))))
          (number "A13" (effects (font (size 1.27 1.27))))
        )
        (pin bidirectional line (at 0 -33.02 0) (length 5.08)
          (name "PT49B" (effects (font (size 1.27 1.27))))
          (number "A14" (effects (font (size 1.27 1.27))))
        )
        (pin bidirectional line (at 0 -22.86 0) (length 5.08)
          (name "PT54B" (effects (font (size 1.27 1.27))))
          (number "A15" (effects (font (size 1.27 1.27))))
        )
        (pin bidirectional line (at 0 -10.16 0) (length 5.08)
          (name "PT60B" (effects (font (size 1.27 1.27))))
          (number "A16" (effects (font (size 1.27 1.27))))
        )
        (pin bidirectional line (at 0 -7.62 0) (length 5.08)
          (name "PT63A" (effects (font (size 1.27 1.27))))
          (number "A17" (effects (font (size 1.27 1.27))))
        )
        (pin bidirectional line (at 0 -137.16 0) (length 5.08)
          (name "PT6A" (effects (font (size 1.27 1.27))))
          (number "A2" (effects (font (size 1.27 1.27))))
        )
        (pin bidirectional line (at 0 -132.08 0) (length 5.08)
          (name "PT6B" (effects (font (size 1.27 1.27))))
          (number "A3" (effects (font (size 1.27 1.27))))
        )
        (pin bidirectional line (at 0 -129.54 0) (length 5.08)
          (name "PT9A" (effects (font (size 1.27 1.27))))
          (number "A4" (effects (font (size 1.27 1.27))))
        )
        (pin bidirectional line (at 0 -124.46 0) (length 5.08)
          (name "PT9B" (effects (font (size 1.27 1.27))))
          (number "A5" (effects (font (size 1.27 1.27))))
        )
        (pin bidirectional line (at 0 -114.3 0) (length 5.08)
          (name "PT13B" (effects (font (size 1.27 1.27))))
          (number "A7" (effects (font (size 1.27 1.27))))
        )
        (pin bidirectional line (at 0 -101.6 0) (length 5.08)
          (name "PT20B" (effects (font (size 1.27 1.27))))
          (number "A8" (effects (font (size 1.27 1.27))))
        )
        (pin bidirectional line (at 0 -91.44 0) (length 5.08)
          (name "PT24B" (effects (font (size 1.27 1.27))))
          (number "A9" (effects (font (size 1.27 1.27))))
        )
        (pin bidirectional line (at 0 -78.74 0) (length 5.08)
          (name "PT31A" (effects (font (size 1.27 1.27))))
          (number "B10" (effects (font (size 1.27 1.27))))
        )
        (pin bidirectional line (at 0 -66.04 0) (length 5.08)
          (name "PT38A" (effects (font (size 1.27 1.27))))
          (number "B11" (effects (font (size 1.27 1.27))))
        )
        (pin bidirectional line (at 0 -38.1 0) (length 5.08)
          (name "PT49A" (effects (font (size 1.27 1.27))))
          (number "B14" (effects (font (size 1.27 1.27))))
        )
        (pin bidirectional line (at 0 -15.24 0) (length 5.08)
          (name "PT60A" (effects (font (size 1.27 1.27))))
          (number "B16" (effects (font (size 1.27 1.27))))
        )
        (pin bidirectional line (at 0 -2.54 0) (length 5.08)
          (name "PT63B" (effects (font (size 1.27 1.27))))
          (number "B17" (effects (font (size 1.27 1.27))))
        )
        (pin bidirectional line (at 0 -139.7 0) (length 5.08)
          (name "PT4A" (effects (font (size 1.27 1.27))))
          (number "B3" (effects (font (size 1.27 1.27))))
        )
        (pin bidirectional line (at 0 -134.62 0) (length 5.08)
          (name "PT4B" (effects (font (size 1.27 1.27))))
          (number "B4" (effects (font (size 1.27 1.27))))
        )
        (pin bidirectional line (at 0 -119.38 0) (length 5.08)
          (name "PT13A" (effects (font (size 1.27 1.27))))
          (number "B7" (effects (font (size 1.27 1.27))))
        )
        (pin bidirectional line (at 0 -106.68 0) (length 5.08)
          (name "PT20A" (effects (font (size 1.27 1.27))))
          (number "B8" (effects (font (size 1.27 1.27))))
        )
        (pin bidirectional line (at 0 -81.28 0) (length 5.08)
          (name "PT29B" (effects (font (size 1.27 1.27))))
          (number "C10" (effects (font (size 1.27 1.27))))
        )
        (pin bidirectional line (at 0 -63.5 0) (length 5.08)
          (name "PT36B" (effects (font (size 1.27 1.27))))
          (number "C11" (effects (font (size 1.27 1.27))))
        )
        (pin bidirectional line (at 0 -55.88 0) (length 5.08)
          (name "PT42A" (effects (font (size 1.27 1.27))))
          (number "C13" (effects (font (size 1.27 1.27))))
        )
        (pin bidirectional line (at 0 -40.64 0) (length 5.08)
          (name "PT47B" (effects (font (size 1.27 1.27))))
          (number "C14" (effects (font (size 1.27 1.27))))
        )
        (pin bidirectional line (at 0 -27.94 0) (length 5.08)
          (name "PT54A" (effects (font (size 1.27 1.27))))
          (number "C15" (effects (font (size 1.27 1.27))))
        )
        (pin bidirectional line (at 0 -12.7 0) (length 5.08)
          (name "PT58B" (effects (font (size 1.27 1.27))))
          (number "C16" (effects (font (size 1.27 1.27))))
        )
        (pin bidirectional line (at 0 -5.08 0) (length 5.08)
          (name "PT65A" (effects (font (size 1.27 1.27))))
          (number "C17" (effects (font (size 1.27 1.27))))
        )
        (pin bidirectional line (at 0 -121.92 0) (length 5.08)
          (name "PT11B" (effects (font (size 1.27 1.27))))
          (number "C7" (effects (font (size 1.27 1.27))))
        )
        (pin bidirectional line (at 0 -104.14 0) (length 5.08)
          (name "PT18B" (effects (font (size 1.27 1.27))))
          (number "C8" (effects (font (size 1.27 1.27))))
        )
        (pin bidirectional line (at 0 -96.52 0) (length 5.08)
          (name "PT24A" (effects (font (size 1.27 1.27))))
          (number "C9" (effects (font (size 1.27 1.27))))
        )
        (pin bidirectional line (at 0 -86.36 0) (length 5.08)
          (name "PT29A" (effects (font (size 1.27 1.27))))
          (number "D10" (effects (font (size 1.27 1.27))))
        )
        (pin bidirectional line (at 0 -68.58 0) (length 5.08)
          (name "PT36A" (effects (font (size 1.27 1.27))))
          (number "D11" (effects (font (size 1.27 1.27))))
        )
        (pin bidirectional line (at 0 -53.34 0) (length 5.08)
          (name "PT40B" (effects (font (size 1.27 1.27))))
          (number "D13" (effects (font (size 1.27 1.27))))
        )
        (pin bidirectional line (at 0 -45.72 0) (length 5.08)
          (name "PT47A" (effects (font (size 1.27 1.27))))
          (number "D14" (effects (font (size 1.27 1.27))))
        )
        (pin bidirectional line (at 0 -30.48 0) (length 5.08)
          (name "PT51B" (effects (font (size 1.27 1.27))))
          (number "D15" (effects (font (size 1.27 1.27))))
        )
        (pin bidirectional line (at 0 -17.78 0) (length 5.08)
          (name "PT58A" (effects (font (size 1.27 1.27))))
          (number "D16" (effects (font (size 1.27 1.27))))
        )
        (pin bidirectional line (at 0 0 0) (length 5.08)
          (name "PT65B" (effects (font (size 1.27 1.27))))
          (number "D17" (effects (font (size 1.27 1.27))))
        )
        (pin bidirectional line (at 0 -127 0) (length 5.08)
          (name "PT11A" (effects (font (size 1.27 1.27))))
          (number "D7" (effects (font (size 1.27 1.27))))
        )
        (pin bidirectional line (at 0 -109.22 0) (length 5.08)
          (name "PT18A" (effects (font (size 1.27 1.27))))
          (number "D8" (effects (font (size 1.27 1.27))))
        )
        (pin bidirectional line (at 0 -93.98 0) (length 5.08)
          (name "PT22B" (effects (font (size 1.27 1.27))))
          (number "D9" (effects (font (size 1.27 1.27))))
        )
        (pin bidirectional line (at 0 -83.82 0) (length 5.08)
          (name "PT27B" (effects (font (size 1.27 1.27))))
          (number "E10" (effects (font (size 1.27 1.27))))
        )
        (pin bidirectional line (at 0 -71.12 0) (length 5.08)
          (name "PT33B" (effects (font (size 1.27 1.27))))
          (number "E11" (effects (font (size 1.27 1.27))))
        )
        (pin bidirectional line (at 0 -43.18 0) (length 5.08)
          (name "PT45B" (effects (font (size 1.27 1.27))))
          (number "E14" (effects (font (size 1.27 1.27))))
        )
        (pin bidirectional line (at 0 -20.32 0) (length 5.08)
          (name "PT56B" (effects (font (size 1.27 1.27))))
          (number "E16" (effects (font (size 1.27 1.27))))
        )
        (pin bidirectional line (at 0 -111.76 0) (length 5.08)
          (name "PT15B" (effects (font (size 1.27 1.27))))
          (number "E8" (effects (font (size 1.27 1.27))))
        )
        (pin bidirectional line (at 0 -88.9 0) (length 5.08)
          (name "PT27A" (effects (font (size 1.27 1.27))))
          (number "F10" (effects (font (size 1.27 1.27))))
        )
        (pin bidirectional line (at 0 -76.2 0) (length 5.08)
          (name "PT33A" (effects (font (size 1.27 1.27))))
          (number "F11" (effects (font (size 1.27 1.27))))
        )
        (pin bidirectional line (at 0 -58.42 0) (length 5.08)
          (name "PT40A" (effects (font (size 1.27 1.27))))
          (number "F13" (effects (font (size 1.27 1.27))))
        )
        (pin bidirectional line (at 0 -48.26 0) (length 5.08)
          (name "PT45A" (effects (font (size 1.27 1.27))))
          (number "F14" (effects (font (size 1.27 1.27))))
        )
        (pin bidirectional line (at 0 -35.56 0) (length 5.08)
          (name "PT51A" (effects (font (size 1.27 1.27))))
          (number "F15" (effects (font (size 1.27 1.27))))
        )
        (pin bidirectional line (at 0 -25.4 0) (length 5.08)
          (name "PT56A" (effects (font (size 1.27 1.27))))
          (number "F16" (effects (font (size 1.27 1.27))))
        )
        (pin bidirectional line (at 0 -116.84 0) (length 5.08)
          (name "PT15A" (effects (font (size 1.27 1.27))))
          (number "F8" (effects (font (size 1.27 1.27))))
        )
        (pin bidirectional line (at 0 -99.06 0) (length 5.08)
          (name "PT22A" (effects (font (size 1.27 1.27))))
          (number "F9" (effects (font (size 1.27 1.27))))
        )
        (pin power_in line (at 27.94 0 180) (length 5.08)
          (name "VCCIO0" (effects (font (size 1.27 1.27))))
          (number "K12" (effects (font (size 1.27 1.27))))
        )
        (pin passive line (at 27.94 0 180) (length 5.08) hide
          (name "VCCIO0" (effects (font (size 1.27 1.27))))
          (number "K14" (effects (font (size 1.27 1.27))))
        )
        (pin passive line (at 27.94 0 180) (length 5.08) hide
          (name "VCCIO0" (effects (font (size 1.27 1.27))))
          (number "K15" (effects (font (size 1.27 1.27))))
        )
        (pin passive line (at 27.94 0 180) (length 5.08) hide
          (name "VCCIO0" (effects (font (size 1.27 1.27))))
          (number "K16" (effects (font (size 1.27 1.27))))
        )
      )
      (symbol "ECP5_LFE5UM5G-85_3_1"
        (rectangle (start 5.08 2.54) (end 22.86 -121.92)
          (stroke (width 0.254) (type default))
          (fill (type background))
        )
        (pin bidirectional line (at 0 -116.84 0) (length 5.08)
          (name "PT71A" (effects (font (size 1.27 1.27))))
          (number "A18" (effects (font (size 1.27 1.27))))
        )
        (pin bidirectional line (at 0 -106.68 0) (length 5.08)
          (name "PT76A" (effects (font (size 1.27 1.27))))
          (number "A19" (effects (font (size 1.27 1.27))))
        )
        (pin bidirectional line (at 0 -88.9 0) (length 5.08)
          (name "PT83A" (effects (font (size 1.27 1.27))))
          (number "A20" (effects (font (size 1.27 1.27))))
        )
        (pin bidirectional line (at 0 -78.74 0) (length 5.08)
          (name "PT87A" (effects (font (size 1.27 1.27))))
          (number "A22" (effects (font (size 1.27 1.27))))
        )
        (pin bidirectional line (at 0 -66.04 0) (length 5.08)
          (name "PT94A" (effects (font (size 1.27 1.27))))
          (number "A23" (effects (font (size 1.27 1.27))))
        )
        (pin bidirectional line (at 0 -48.26 0) (length 5.08)
          (name "PT101A" (effects (font (size 1.27 1.27))))
          (number "A24" (effects (font (size 1.27 1.27))))
        )
        (pin bidirectional line (at 0 -38.1 0) (length 5.08)
          (name "PT105A" (effects (font (size 1.27 1.27))))
          (number "A25" (effects (font (size 1.27 1.27))))
        )
        (pin bidirectional line (at 0 -25.4 0) (length 5.08)
          (name "PT112A" (effects (font (size 1.27 1.27))))
          (number "A26" (effects (font (size 1.27 1.27))))
        )
        (pin bidirectional line (at 0 -15.24 0) (length 5.08)
          (name "PT116A" (effects (font (size 1.27 1.27))))
          (number "A28" (effects (font (size 1.27 1.27))))
        )
        (pin bidirectional line (at 0 -10.16 0) (length 5.08)
          (name "PT116B" (effects (font (size 1.27 1.27))))
          (number "A29" (effects (font (size 1.27 1.27))))
        )
        (pin bidirectional line (at 0 -7.62 0) (length 5.08)
          (name "PT119A" (effects (font (size 1.27 1.27))))
          (number "A30" (effects (font (size 1.27 1.27))))
        )
        (pin bidirectional line (at 0 -2.54 0) (length 5.08)
          (name "PT119B" (effects (font (size 1.27 1.27))))
          (number "A31" (effects (font (size 1.27 1.27))))
        )
        (pin bidirectional line (at 0 -101.6 0) (length 5.08)
          (name "PT76B" (effects (font (size 1.27 1.27))))
          (number "B19" (effects (font (size 1.27 1.27))))
        )
        (pin bidirectional line (at 0 -73.66 0) (length 5.08)
          (name "PT87B" (effects (font (size 1.27 1.27))))
          (number "B22" (effects (font (size 1.27 1.27))))
        )
        (pin bidirectional line (at 0 -60.96 0) (length 5.08)
          (name "PT94B" (effects (font (size 1.27 1.27))))
          (number "B23" (effects (font (size 1.27 1.27))))
        )
        (pin bidirectional line (at 0 -33.02 0) (length 5.08)
          (name "PT105B" (effects (font (size 1.27 1.27))))
          (number "B25" (effects (font (size 1.27 1.27))))
        )
        (pin bidirectional line (at 0 -20.32 0) (length 5.08)
          (name "PT112B" (effects (font (size 1.27 1.27))))
          (number "B26" (effects (font (size 1.27 1.27))))
        )
        (pin bidirectional line (at 0 -5.08 0) (length 5.08)
          (name "PT121A" (effects (font (size 1.27 1.27))))
          (number "B29" (effects (font (size 1.27 1.27))))
        )
        (pin bidirectional line (at 0 0 0) (length 5.08)
          (name "PT121B" (effects (font (size 1.27 1.27))))
          (number "B30" (effects (font (size 1.27 1.27))))
        )
        (pin bidirectional line (at 0 -111.76 0) (length 5.08)
          (name "PT71B" (effects (font (size 1.27 1.27))))
          (number "C18" (effects (font (size 1.27 1.27))))
        )
        (pin bidirectional line (at 0 -99.06 0) (length 5.08)
          (name "PT78A" (effects (font (size 1.27 1.27))))
          (number "C19" (effects (font (size 1.27 1.27))))
        )
        (pin bidirectional line (at 0 -83.82 0) (length 5.08)
          (name "PT83B" (effects (font (size 1.27 1.27))))
          (number "C20" (effects (font (size 1.27 1.27))))
        )
        (pin bidirectional line (at 0 -76.2 0) (length 5.08)
          (name "PT89A" (effects (font (size 1.27 1.27))))
          (number "C22" (effects (font (size 1.27 1.27))))
        )
        (pin bidirectional line (at 0 -58.42 0) (length 5.08)
          (name "PT96A" (effects (font (size 1.27 1.27))))
          (number "C23" (effects (font (size 1.27 1.27))))
        )
        (pin bidirectional line (at 0 -43.18 0) (length 5.08)
          (name "PT101B" (effects (font (size 1.27 1.27))))
          (number "C24" (effects (font (size 1.27 1.27))))
        )
        (pin bidirectional line (at 0 -35.56 0) (length 5.08)
          (name "PT107A" (effects (font (size 1.27 1.27))))
          (number "C25" (effects (font (size 1.27 1.27))))
        )
        (pin bidirectional line (at 0 -17.78 0) (length 5.08)
          (name "PT114A" (effects (font (size 1.27 1.27))))
          (number "C26" (effects (font (size 1.27 1.27))))
        )
        (pin bidirectional line (at 0 -109.22 0) (length 5.08)
          (name "PT74A" (effects (font (size 1.27 1.27))))
          (number "D18" (effects (font (size 1.27 1.27))))
        )
        (pin bidirectional line (at 0 -93.98 0) (length 5.08)
          (name "PT78B" (effects (font (size 1.27 1.27))))
          (number "D19" (effects (font (size 1.27 1.27))))
        )
        (pin bidirectional line (at 0 -86.36 0) (length 5.08)
          (name "PT85A" (effects (font (size 1.27 1.27))))
          (number "D20" (effects (font (size 1.27 1.27))))
        )
        (pin bidirectional line (at 0 -71.12 0) (length 5.08)
          (name "PT89B" (effects (font (size 1.27 1.27))))
          (number "D22" (effects (font (size 1.27 1.27))))
        )
        (pin bidirectional line (at 0 -53.34 0) (length 5.08)
          (name "PT96B" (effects (font (size 1.27 1.27))))
          (number "D23" (effects (font (size 1.27 1.27))))
        )
        (pin bidirectional line (at 0 -45.72 0) (length 5.08)
          (name "PT103A" (effects (font (size 1.27 1.27))))
          (number "D24" (effects (font (size 1.27 1.27))))
        )
        (pin bidirectional line (at 0 -30.48 0) (length 5.08)
          (name "PT107B" (effects (font (size 1.27 1.27))))
          (number "D25" (effects (font (size 1.27 1.27))))
        )
        (pin bidirectional line (at 0 -12.7 0) (length 5.08)
          (name "PT114B" (effects (font (size 1.27 1.27))))
          (number "D26" (effects (font (size 1.27 1.27))))
        )
        (pin bidirectional line (at 0 -119.38 0) (length 5.08)
          (name "PT69A" (effects (font (size 1.27 1.27))))
          (number "E17" (effects (font (size 1.27 1.27))))
        )
        (pin bidirectional line (at 0 -96.52 0) (length 5.08)
          (name "PT80A" (effects (font (size 1.27 1.27))))
          (number "E19" (effects (font (size 1.27 1.27))))
        )
        (pin bidirectional line (at 0 -68.58 0) (length 5.08)
          (name "PT92A" (effects (font (size 1.27 1.27))))
          (number "E22" (effects (font (size 1.27 1.27))))
        )
        (pin bidirectional line (at 0 -55.88 0) (length 5.08)
          (name "PT98A" (effects (font (size 1.27 1.27))))
          (number "E23" (effects (font (size 1.27 1.27))))
        )
        (pin bidirectional line (at 0 -27.94 0) (length 5.08)
          (name "PT110A" (effects (font (size 1.27 1.27))))
          (number "E25" (effects (font (size 1.27 1.27))))
        )
        (pin bidirectional line (at 0 -114.3 0) (length 5.08)
          (name "PT69B" (effects (font (size 1.27 1.27))))
          (number "F17" (effects (font (size 1.27 1.27))))
        )
        (pin bidirectional line (at 0 -104.14 0) (length 5.08)
          (name "PT74B" (effects (font (size 1.27 1.27))))
          (number "F18" (effects (font (size 1.27 1.27))))
        )
        (pin bidirectional line (at 0 -91.44 0) (length 5.08)
          (name "PT80B" (effects (font (size 1.27 1.27))))
          (number "F19" (effects (font (size 1.27 1.27))))
        )
        (pin bidirectional line (at 0 -81.28 0) (length 5.08)
          (name "PT85B" (effects (font (size 1.27 1.27))))
          (number "F20" (effects (font (size 1.27 1.27))))
        )
        (pin bidirectional line (at 0 -63.5 0) (length 5.08)
          (name "PT92B" (effects (font (size 1.27 1.27))))
          (number "F22" (effects (font (size 1.27 1.27))))
        )
        (pin bidirectional line (at 0 -50.8 0) (length 5.08)
          (name "PT98B" (effects (font (size 1.27 1.27))))
          (number "F23" (effects (font (size 1.27 1.27))))
        )
        (pin bidirectional line (at 0 -40.64 0) (length 5.08)
          (name "PT103B" (effects (font (size 1.27 1.27))))
          (number "F24" (effects (font (size 1.27 1.27))))
        )
        (pin bidirectional line (at 0 -22.86 0) (length 5.08)
          (name "PT110B" (effects (font (size 1.27 1.27))))
          (number "F25" (effects (font (size 1.27 1.27))))
        )
        (pin power_in line (at 27.94 0 180) (length 5.08)
          (name "VCCIO1" (effects (font (size 1.27 1.27))))
          (number "K17" (effects (font (size 1.27 1.27))))
        )
        (pin passive line (at 27.94 0 180) (length 5.08) hide
          (name "VCCIO1" (effects (font (size 1.27 1.27))))
          (number "K18" (effects (font (size 1.27 1.27))))
        )
        (pin passive line (at 27.94 0 180) (length 5.08) hide
          (name "VCCIO1" (effects (font (size 1.27 1.27))))
          (number "K19" (effects (font (size 1.27 1.27))))
        )
        (pin passive line (at 27.94 0 180) (length 5.08) hide
          (name "VCCIO1" (effects (font (size 1.27 1.27))))
          (number "K21" (effects (font (size 1.27 1.27))))
        )
      )
      (symbol "ECP5_LFE5UM5G-85_4_1"
        (rectangle (start 5.08 2.54) (end 22.86 -121.92)
          (stroke (width 0.254) (type default))
          (fill (type background))
        )
        (pin bidirectional line (at 0 -99.06 0) (length 5.08)
          (name "PR17A" (effects (font (size 1.27 1.27))))
          (number "B32" (effects (font (size 1.27 1.27))))
        )
        (pin bidirectional line (at 0 -119.38 0) (length 5.08)
          (name "PR11A" (effects (font (size 1.27 1.27))))
          (number "C28" (effects (font (size 1.27 1.27))))
        )
        (pin bidirectional line (at 0 -114.3 0) (length 5.08)
          (name "PR11C" (effects (font (size 1.27 1.27))))
          (number "C29" (effects (font (size 1.27 1.27))))
        )
        (pin bidirectional line (at 0 -111.76 0) (length 5.08)
          (name "PR11D" (effects (font (size 1.27 1.27))))
          (number "C30" (effects (font (size 1.27 1.27))))
        )
        (pin bidirectional line (at 0 -93.98 0) (length 5.08)
          (name "PR17B" (effects (font (size 1.27 1.27))))
          (number "C31" (effects (font (size 1.27 1.27))))
        )
        (pin bidirectional line (at 0 -86.36 0) (length 5.08)
          (name "PR20C" (effects (font (size 1.27 1.27))))
          (number "C32" (effects (font (size 1.27 1.27))))
        )
        (pin bidirectional line (at 0 -116.84 0) (length 5.08)
          (name "PR11B" (effects (font (size 1.27 1.27))))
          (number "D28" (effects (font (size 1.27 1.27))))
        )
        (pin bidirectional line (at 0 -109.22 0) (length 5.08)
          (name "PR14A" (effects (font (size 1.27 1.27))))
          (number "D29" (effects (font (size 1.27 1.27))))
        )
        (pin bidirectional line (at 0 -96.52 0) (length 5.08)
          (name "PR17C" (effects (font (size 1.27 1.27))))
          (number "D30" (effects (font (size 1.27 1.27))))
        )
        (pin bidirectional line (at 0 -91.44 0) (length 5.08)
          (name "PR17D" (effects (font (size 1.27 1.27))))
          (number "D31" (effects (font (size 1.27 1.27))))
        )
        (pin bidirectional line (at 0 -81.28 0) (length 5.08)
          (name "PR20D" (effects (font (size 1.27 1.27))))
          (number "D32" (effects (font (size 1.27 1.27))))
        )
        (pin bidirectional line (at 0 -104.14 0) (length 5.08)
          (name "PR14B" (effects (font (size 1.27 1.27))))
          (number "E29" (effects (font (size 1.27 1.27))))
        )
        (pin bidirectional line (at 0 -83.82 0) (length 5.08)
          (name "PR20B" (effects (font (size 1.27 1.27))))
          (number "E30" (effects (font (size 1.27 1.27))))
        )
        (pin bidirectional line (at 0 -73.66 0) (length 5.08)
          (name "PR23B" (effects (font (size 1.27 1.27))))
          (number "E32" (effects (font (size 1.27 1.27))))
        )
        (pin bidirectional line (at 0 -101.6 0) (length 5.08)
          (name "PR14D" (effects (font (size 1.27 1.27))))
          (number "F28" (effects (font (size 1.27 1.27))))
        )
        (pin bidirectional line (at 0 -106.68 0) (length 5.08)
          (name "PR14C" (effects (font (size 1.27 1.27))))
          (number "F29" (effects (font (size 1.27 1.27))))
        )
        (pin bidirectional line (at 0 -88.9 0) (length 5.08)
          (name "PR20A" (effects (font (size 1.27 1.27))))
          (number "F30" (effects (font (size 1.27 1.27))))
        )
        (pin bidirectional line (at 0 -78.74 0) (length 5.08)
          (name "PR23A" (effects (font (size 1.27 1.27))))
          (number "F31" (effects (font (size 1.27 1.27))))
        )
        (pin bidirectional line (at 0 -76.2 0) (length 5.08)
          (name "PR23C" (effects (font (size 1.27 1.27))))
          (number "F32" (effects (font (size 1.27 1.27))))
        )
        (pin bidirectional line (at 0 -38.1 0) (length 5.08)
          (name "PR35A" (effects (font (size 1.27 1.27))))
          (number "H27" (effects (font (size 1.27 1.27))))
        )
        (pin bidirectional line (at 0 -33.02 0) (length 5.08)
          (name "PR35B" (effects (font (size 1.27 1.27))))
          (number "H28" (effects (font (size 1.27 1.27))))
        )
        (pin bidirectional line (at 0 -63.5 0) (length 5.08)
          (name "PR26B" (effects (font (size 1.27 1.27))))
          (number "H30" (effects (font (size 1.27 1.27))))
        )
        (pin bidirectional line (at 0 -68.58 0) (length 5.08)
          (name "PR26A" (effects (font (size 1.27 1.27))))
          (number "H31" (effects (font (size 1.27 1.27))))
        )
        (pin bidirectional line (at 0 -71.12 0) (length 5.08)
          (name "PR23D" (effects (font (size 1.27 1.27))))
          (number "H32" (effects (font (size 1.27 1.27))))
        )
        (pin bidirectional line (at 0 -35.56 0) (length 5.08)
          (name "PR35C" (effects (font (size 1.27 1.27))))
          (number "J26" (effects (font (size 1.27 1.27))))
        )
        (pin bidirectional line (at 0 -30.48 0) (length 5.08)
          (name "PR35D" (effects (font (size 1.27 1.27))))
          (number "J27" (effects (font (size 1.27 1.27))))
        )
        (pin bidirectional line (at 0 -45.72 0) (length 5.08)
          (name "PR32C" (effects (font (size 1.27 1.27))))
          (number "J29" (effects (font (size 1.27 1.27))))
        )
        (pin bidirectional line (at 0 -66.04 0) (length 5.08)
          (name "PR26C" (effects (font (size 1.27 1.27))))
          (number "J30" (effects (font (size 1.27 1.27))))
        )
        (pin bidirectional line (at 0 -53.34 0) (length 5.08)
          (name "PR29B" (effects (font (size 1.27 1.27))))
          (number "J32" (effects (font (size 1.27 1.27))))
        )
        (pin bidirectional line (at 0 -22.86 0) (length 5.08)
          (name "PR38B" (effects (font (size 1.27 1.27))))
          (number "K26" (effects (font (size 1.27 1.27))))
        )
        (pin bidirectional line (at 0 -27.94 0) (length 5.08)
          (name "PR38A" (effects (font (size 1.27 1.27))))
          (number "K27" (effects (font (size 1.27 1.27))))
        )
        (pin bidirectional line (at 0 -25.4 0) (length 5.08)
          (name "PR38C" (effects (font (size 1.27 1.27))))
          (number "K28" (effects (font (size 1.27 1.27))))
        )
        (pin bidirectional line (at 0 -40.64 0) (length 5.08)
          (name "PR32D" (effects (font (size 1.27 1.27))))
          (number "K29" (effects (font (size 1.27 1.27))))
        )
        (pin bidirectional line (at 0 -60.96 0) (length 5.08)
          (name "PR26D" (effects (font (size 1.27 1.27))))
          (number "K30" (effects (font (size 1.27 1.27))))
        )
        (pin bidirectional line (at 0 -58.42 0) (length 5.08)
          (name "PR29A" (effects (font (size 1.27 1.27))))
          (number "K31" (effects (font (size 1.27 1.27))))
        )
        (pin bidirectional line (at 0 -55.88 0) (length 5.08)
          (name "PR29C" (effects (font (size 1.27 1.27))))
          (number "K32" (effects (font (size 1.27 1.27))))
        )
        (pin bidirectional line (at 0 -15.24 0) (length 5.08)
          (name "PR41C" (effects (font (size 1.27 1.27))))
          (number "L26" (effects (font (size 1.27 1.27))))
        )
        (pin bidirectional line (at 0 -10.16 0) (length 5.08)
          (name "PR41D" (effects (font (size 1.27 1.27))))
          (number "L27" (effects (font (size 1.27 1.27))))
        )
        (pin bidirectional line (at 0 -20.32 0) (length 5.08)
          (name "PR38D" (effects (font (size 1.27 1.27))))
          (number "L29" (effects (font (size 1.27 1.27))))
        )
        (pin bidirectional line (at 0 -43.18 0) (length 5.08)
          (name "PR32B" (effects (font (size 1.27 1.27))))
          (number "L30" (effects (font (size 1.27 1.27))))
        )
        (pin bidirectional line (at 0 -48.26 0) (length 5.08)
          (name "PR32A" (effects (font (size 1.27 1.27))))
          (number "L31" (effects (font (size 1.27 1.27))))
        )
        (pin bidirectional line (at 0 -50.8 0) (length 5.08)
          (name "PR29D" (effects (font (size 1.27 1.27))))
          (number "L32" (effects (font (size 1.27 1.27))))
        )
        (pin power_in line (at 27.94 0 180) (length 5.08)
          (name "VCCIO2" (effects (font (size 1.27 1.27))))
          (number "M23" (effects (font (size 1.27 1.27))))
        )
        (pin bidirectional line (at 0 -2.54 0) (length 5.08)
          (name "PR44B" (effects (font (size 1.27 1.27))))
          (number "N26" (effects (font (size 1.27 1.27))))
        )
        (pin bidirectional line (at 0 -7.62 0) (length 5.08)
          (name "PR44A" (effects (font (size 1.27 1.27))))
          (number "N27" (effects (font (size 1.27 1.27))))
        )
        (pin bidirectional line (at 0 -12.7 0) (length 5.08)
          (name "PR41B" (effects (font (size 1.27 1.27))))
          (number "N29" (effects (font (size 1.27 1.27))))
        )
        (pin bidirectional line (at 0 -17.78 0) (length 5.08)
          (name "PR41A" (effects (font (size 1.27 1.27))))
          (number "N30" (effects (font (size 1.27 1.27))))
        )
        (pin passive line (at 27.94 0 180) (length 5.08) hide
          (name "VCCIO2" (effects (font (size 1.27 1.27))))
          (number "P23" (effects (font (size 1.27 1.27))))
        )
        (pin bidirectional line (at 0 0 0) (length 5.08)
          (name "PR44D" (effects (font (size 1.27 1.27))))
          (number "P26" (effects (font (size 1.27 1.27))))
        )
        (pin bidirectional line (at 0 -5.08 0) (length 5.08)
          (name "PR44C" (effects (font (size 1.27 1.27))))
          (number "P27" (effects (font (size 1.27 1.27))))
        )
        (pin passive line (at 27.94 0 180) (length 5.08) hide
          (name "VCCIO2" (effects (font (size 1.27 1.27))))
          (number "R23" (effects (font (size 1.27 1.27))))
        )
        (pin passive line (at 27.94 0 180) (length 5.08) hide
          (name "VCCIO2" (effects (font (size 1.27 1.27))))
          (number "T23" (effects (font (size 1.27 1.27))))
        )
      )
      (symbol "ECP5_LFE5UM5G-85_5_1"
        (rectangle (start 5.08 2.54) (end 22.86 -162.56)
          (stroke (width 0.254) (type default))
          (fill (type background))
        )
        (pin power_in line (at 27.94 0 180) (length 5.08)
          (name "VCCIO3" (effects (font (size 1.27 1.27))))
          (number "AA23" (effects (font (size 1.27 1.27))))
        )
        (pin bidirectional line (at 0 -66.04 0) (length 5.08)
          (name "PR74C" (effects (font (size 1.27 1.27))))
          (number "AB26" (effects (font (size 1.27 1.27))))
        )
        (pin bidirectional line (at 0 -53.34 0) (length 5.08)
          (name "PR77B" (effects (font (size 1.27 1.27))))
          (number "AB27" (effects (font (size 1.27 1.27))))
        )
        (pin bidirectional line (at 0 -58.42 0) (length 5.08)
          (name "PR77A" (effects (font (size 1.27 1.27))))
          (number "AB28" (effects (font (size 1.27 1.27))))
        )
        (pin bidirectional line (at 0 -33.02 0) (length 5.08)
          (name "PR83B" (effects (font (size 1.27 1.27))))
          (number "AB29" (effects (font (size 1.27 1.27))))
        )
        (pin bidirectional line (at 0 -38.1 0) (length 5.08)
          (name "PR83A" (effects (font (size 1.27 1.27))))
          (number "AB30" (effects (font (size 1.27 1.27))))
        )
        (pin bidirectional line (at 0 -12.7 0) (length 5.08)
          (name "PR89B" (effects (font (size 1.27 1.27))))
          (number "AB31" (effects (font (size 1.27 1.27))))
        )
        (pin bidirectional line (at 0 -7.62 0) (length 5.08)
          (name "PR92A" (effects (font (size 1.27 1.27))))
          (number "AB32" (effects (font (size 1.27 1.27))))
        )
        (pin bidirectional line (at 0 -55.88 0) (length 5.08)
          (name "PR77C" (effects (font (size 1.27 1.27))))
          (number "AC26" (effects (font (size 1.27 1.27))))
        )
        (pin bidirectional line (at 0 -60.96 0) (length 5.08)
          (name "PR74D" (effects (font (size 1.27 1.27))))
          (number "AC27" (effects (font (size 1.27 1.27))))
        )
        (pin bidirectional line (at 0 -35.56 0) (length 5.08)
          (name "PR83C" (effects (font (size 1.27 1.27))))
          (number "AC28" (effects (font (size 1.27 1.27))))
        )
        (pin bidirectional line (at 0 -17.78 0) (length 5.08)
          (name "PR89A" (effects (font (size 1.27 1.27))))
          (number "AC30" (effects (font (size 1.27 1.27))))
        )
        (pin bidirectional line (at 0 -15.24 0) (length 5.08)
          (name "PR89C" (effects (font (size 1.27 1.27))))
          (number "AC31" (effects (font (size 1.27 1.27))))
        )
        (pin bidirectional line (at 0 -5.08 0) (length 5.08)
          (name "PR92B" (effects (font (size 1.27 1.27))))
          (number "AC32" (effects (font (size 1.27 1.27))))
        )
        (pin bidirectional line (at 0 -50.8 0) (length 5.08)
          (name "PR77D" (effects (font (size 1.27 1.27))))
          (number "AD26" (effects (font (size 1.27 1.27))))
        )
        (pin bidirectional line (at 0 -48.26 0) (length 5.08)
          (name "PR80A" (effects (font (size 1.27 1.27))))
          (number "AD27" (effects (font (size 1.27 1.27))))
        )
        (pin bidirectional line (at 0 -30.48 0) (length 5.08)
          (name "PR83D" (effects (font (size 1.27 1.27))))
          (number "AD29" (effects (font (size 1.27 1.27))))
        )
        (pin bidirectional line (at 0 -25.4 0) (length 5.08)
          (name "PR86C" (effects (font (size 1.27 1.27))))
          (number "AD30" (effects (font (size 1.27 1.27))))
        )
        (pin bidirectional line (at 0 -2.54 0) (length 5.08)
          (name "PR92C" (effects (font (size 1.27 1.27))))
          (number "AD32" (effects (font (size 1.27 1.27))))
        )
        (pin bidirectional line (at 0 -43.18 0) (length 5.08)
          (name "PR80B" (effects (font (size 1.27 1.27))))
          (number "AE27" (effects (font (size 1.27 1.27))))
        )
        (pin bidirectional line (at 0 -45.72 0) (length 5.08)
          (name "PR80C" (effects (font (size 1.27 1.27))))
          (number "AE28" (effects (font (size 1.27 1.27))))
        )
        (pin bidirectional line (at 0 -40.64 0) (length 5.08)
          (name "PR80D" (effects (font (size 1.27 1.27))))
          (number "AE29" (effects (font (size 1.27 1.27))))
        )
        (pin bidirectional line (at 0 -20.32 0) (length 5.08)
          (name "PR86D" (effects (font (size 1.27 1.27))))
          (number "AE30" (effects (font (size 1.27 1.27))))
        )
        (pin bidirectional line (at 0 -10.16 0) (length 5.08)
          (name "PR89D" (effects (font (size 1.27 1.27))))
          (number "AE31" (effects (font (size 1.27 1.27))))
        )
        (pin bidirectional line (at 0 0 0) (length 5.08)
          (name "PR92D" (effects (font (size 1.27 1.27))))
          (number "AE32" (effects (font (size 1.27 1.27))))
        )
        (pin bidirectional line (at 0 -109.22 0) (length 5.08)
          (name "PR62A" (effects (font (size 1.27 1.27))))
          (number "N32" (effects (font (size 1.27 1.27))))
        )
        (pin bidirectional line (at 0 -160.02 0) (length 5.08)
          (name "PR47A" (effects (font (size 1.27 1.27))))
          (number "P28" (effects (font (size 1.27 1.27))))
        )
        (pin bidirectional line (at 0 -154.94 0) (length 5.08)
          (name "PR47B" (effects (font (size 1.27 1.27))))
          (number "P29" (effects (font (size 1.27 1.27))))
        )
        (pin bidirectional line (at 0 -114.3 0) (length 5.08)
          (name "PR59B" (effects (font (size 1.27 1.27))))
          (number "P30" (effects (font (size 1.27 1.27))))
        )
        (pin bidirectional line (at 0 -119.38 0) (length 5.08)
          (name "PR59A" (effects (font (size 1.27 1.27))))
          (number "P31" (effects (font (size 1.27 1.27))))
        )
        (pin bidirectional line (at 0 -104.14 0) (length 5.08)
          (name "PR62B" (effects (font (size 1.27 1.27))))
          (number "P32" (effects (font (size 1.27 1.27))))
        )
        (pin bidirectional line (at 0 -157.48 0) (length 5.08)
          (name "PR47C" (effects (font (size 1.27 1.27))))
          (number "R26" (effects (font (size 1.27 1.27))))
        )
        (pin bidirectional line (at 0 -149.86 0) (length 5.08)
          (name "PR50A" (effects (font (size 1.27 1.27))))
          (number "R27" (effects (font (size 1.27 1.27))))
        )
        (pin bidirectional line (at 0 -139.7 0) (length 5.08)
          (name "PR53A" (effects (font (size 1.27 1.27))))
          (number "R29" (effects (font (size 1.27 1.27))))
        )
        (pin bidirectional line (at 0 -116.84 0) (length 5.08)
          (name "PR59C" (effects (font (size 1.27 1.27))))
          (number "R30" (effects (font (size 1.27 1.27))))
        )
        (pin bidirectional line (at 0 -99.06 0) (length 5.08)
          (name "PR65A" (effects (font (size 1.27 1.27))))
          (number "R32" (effects (font (size 1.27 1.27))))
        )
        (pin bidirectional line (at 0 -152.4 0) (length 5.08)
          (name "PR47D" (effects (font (size 1.27 1.27))))
          (number "T26" (effects (font (size 1.27 1.27))))
        )
        (pin bidirectional line (at 0 -144.78 0) (length 5.08)
          (name "PR50B" (effects (font (size 1.27 1.27))))
          (number "T27" (effects (font (size 1.27 1.27))))
        )
        (pin bidirectional line (at 0 -134.62 0) (length 5.08)
          (name "PR53B" (effects (font (size 1.27 1.27))))
          (number "T28" (effects (font (size 1.27 1.27))))
        )
        (pin bidirectional line (at 0 -137.16 0) (length 5.08)
          (name "PR53C" (effects (font (size 1.27 1.27))))
          (number "T29" (effects (font (size 1.27 1.27))))
        )
        (pin bidirectional line (at 0 -111.76 0) (length 5.08)
          (name "PR59D" (effects (font (size 1.27 1.27))))
          (number "T30" (effects (font (size 1.27 1.27))))
        )
        (pin bidirectional line (at 0 -93.98 0) (length 5.08)
          (name "PR65B" (effects (font (size 1.27 1.27))))
          (number "T31" (effects (font (size 1.27 1.27))))
        )
        (pin bidirectional line (at 0 -88.9 0) (length 5.08)
          (name "PR68A" (effects (font (size 1.27 1.27))))
          (number "T32" (effects (font (size 1.27 1.27))))
        )
        (pin passive line (at 27.94 0 180) (length 5.08) hide
          (name "VCCIO3" (effects (font (size 1.27 1.27))))
          (number "U23" (effects (font (size 1.27 1.27))))
        )
        (pin bidirectional line (at 0 -142.24 0) (length 5.08)
          (name "PR50D" (effects (font (size 1.27 1.27))))
          (number "U26" (effects (font (size 1.27 1.27))))
        )
        (pin bidirectional line (at 0 -147.32 0) (length 5.08)
          (name "PR50C" (effects (font (size 1.27 1.27))))
          (number "U27" (effects (font (size 1.27 1.27))))
        )
        (pin bidirectional line (at 0 -132.08 0) (length 5.08)
          (name "PR53D" (effects (font (size 1.27 1.27))))
          (number "U28" (effects (font (size 1.27 1.27))))
        )
        (pin bidirectional line (at 0 -129.54 0) (length 5.08)
          (name "PR56A" (effects (font (size 1.27 1.27))))
          (number "U29" (effects (font (size 1.27 1.27))))
        )
        (pin bidirectional line (at 0 -101.6 0) (length 5.08)
          (name "PR62D" (effects (font (size 1.27 1.27))))
          (number "U30" (effects (font (size 1.27 1.27))))
        )
        (pin bidirectional line (at 0 -106.68 0) (length 5.08)
          (name "PR62C" (effects (font (size 1.27 1.27))))
          (number "U31" (effects (font (size 1.27 1.27))))
        )
        (pin bidirectional line (at 0 -83.82 0) (length 5.08)
          (name "PR68B" (effects (font (size 1.27 1.27))))
          (number "U32" (effects (font (size 1.27 1.27))))
        )
        (pin passive line (at 27.94 0 180) (length 5.08) hide
          (name "VCCIO3" (effects (font (size 1.27 1.27))))
          (number "V23" (effects (font (size 1.27 1.27))))
        )
        (pin bidirectional line (at 0 -121.92 0) (length 5.08)
          (name "PR56D" (effects (font (size 1.27 1.27))))
          (number "V26" (effects (font (size 1.27 1.27))))
        )
        (pin bidirectional line (at 0 -127 0) (length 5.08)
          (name "PR56C" (effects (font (size 1.27 1.27))))
          (number "V27" (effects (font (size 1.27 1.27))))
        )
        (pin bidirectional line (at 0 -124.46 0) (length 5.08)
          (name "PR56B" (effects (font (size 1.27 1.27))))
          (number "V29" (effects (font (size 1.27 1.27))))
        )
        (pin bidirectional line (at 0 -86.36 0) (length 5.08)
          (name "PR68C" (effects (font (size 1.27 1.27))))
          (number "V32" (effects (font (size 1.27 1.27))))
        )
        (pin passive line (at 27.94 0 180) (length 5.08) hide
          (name "VCCIO3" (effects (font (size 1.27 1.27))))
          (number "W23" (effects (font (size 1.27 1.27))))
        )
        (pin bidirectional line (at 0 -71.12 0) (length 5.08)
          (name "PR71D" (effects (font (size 1.27 1.27))))
          (number "W28" (effects (font (size 1.27 1.27))))
        )
        (pin bidirectional line (at 0 -63.5 0) (length 5.08)
          (name "PR74B" (effects (font (size 1.27 1.27))))
          (number "W29" (effects (font (size 1.27 1.27))))
        )
        (pin bidirectional line (at 0 -96.52 0) (length 5.08)
          (name "PR65C" (effects (font (size 1.27 1.27))))
          (number "W30" (effects (font (size 1.27 1.27))))
        )
        (pin bidirectional line (at 0 -27.94 0) (length 5.08)
          (name "PR86A" (effects (font (size 1.27 1.27))))
          (number "W31" (effects (font (size 1.27 1.27))))
        )
        (pin bidirectional line (at 0 -81.28 0) (length 5.08)
          (name "PR68D" (effects (font (size 1.27 1.27))))
          (number "W32" (effects (font (size 1.27 1.27))))
        )
        (pin bidirectional line (at 0 -78.74 0) (length 5.08)
          (name "PR71A" (effects (font (size 1.27 1.27))))
          (number "Y26" (effects (font (size 1.27 1.27))))
        )
        (pin bidirectional line (at 0 -73.66 0) (length 5.08)
          (name "PR71B" (effects (font (size 1.27 1.27))))
          (number "Y27" (effects (font (size 1.27 1.27))))
        )
        (pin bidirectional line (at 0 -76.2 0) (length 5.08)
          (name "PR71C" (effects (font (size 1.27 1.27))))
          (number "Y28" (effects (font (size 1.27 1.27))))
        )
        (pin bidirectional line (at 0 -68.58 0) (length 5.08)
          (name "PR74A" (effects (font (size 1.27 1.27))))
          (number "Y29" (effects (font (size 1.27 1.27))))
        )
        (pin bidirectional line (at 0 -91.44 0) (length 5.08)
          (name "PR65D" (effects (font (size 1.27 1.27))))
          (number "Y30" (effects (font (size 1.27 1.27))))
        )
        (pin bidirectional line (at 0 -22.86 0) (length 5.08)
          (name "PR86B" (effects (font (size 1.27 1.27))))
          (number "Y32" (effects (font (size 1.27 1.27))))
        )
      )
      (symbol "ECP5_LFE5UM5G-85_6_1"
        (rectangle (start 5.08 2.54) (end 22.86 -60.96)
          (stroke (width 0.254) (type default))
          (fill (type background))
        )
        (pin power_in line (at 27.94 0 180) (length 5.08)
          (name "VCCIO4" (effects (font (size 1.27 1.27))))
          (number "AB23" (effects (font (size 1.27 1.27))))
        )
        (pin passive line (at 27.94 0 180) (length 5.08) hide
          (name "VCCIO4" (effects (font (size 1.27 1.27))))
          (number "AC23" (effects (font (size 1.27 1.27))))
        )
        (pin bidirectional line (at 0 -30.48 0) (length 5.08)
          (name "PB110A" (effects (font (size 1.27 1.27))))
          (number "AG28" (effects (font (size 1.27 1.27))))
        )
        (pin bidirectional line (at 0 -35.56 0) (length 5.08)
          (name "PB110B" (effects (font (size 1.27 1.27))))
          (number "AG29" (effects (font (size 1.27 1.27))))
        )
        (pin bidirectional line (at 0 -45.72 0) (length 5.08)
          (name "PB114B" (effects (font (size 1.27 1.27))))
          (number "AG30" (effects (font (size 1.27 1.27))))
        )
        (pin bidirectional line (at 0 -55.88 0) (length 5.08)
          (name "PB119B" (effects (font (size 1.27 1.27))))
          (number "AG32" (effects (font (size 1.27 1.27))))
        )
        (pin bidirectional line (at 0 -38.1 0) (length 5.08)
          (name "PB112B" (effects (font (size 1.27 1.27))))
          (number "AH28" (effects (font (size 1.27 1.27))))
        )
        (pin bidirectional line (at 0 -40.64 0) (length 5.08)
          (name "PB114A" (effects (font (size 1.27 1.27))))
          (number "AH30" (effects (font (size 1.27 1.27))))
        )
        (pin bidirectional line (at 0 -50.8 0) (length 5.08)
          (name "PB119A" (effects (font (size 1.27 1.27))))
          (number "AH32" (effects (font (size 1.27 1.27))))
        )
        (pin bidirectional line (at 0 -33.02 0) (length 5.08)
          (name "PB112A" (effects (font (size 1.27 1.27))))
          (number "AJ28" (effects (font (size 1.27 1.27))))
        )
        (pin bidirectional line (at 0 -53.34 0) (length 5.08)
          (name "PB121A" (effects (font (size 1.27 1.27))))
          (number "AJ29" (effects (font (size 1.27 1.27))))
        )
        (pin bidirectional line (at 0 -58.42 0) (length 5.08)
          (name "PB121B" (effects (font (size 1.27 1.27))))
          (number "AJ30" (effects (font (size 1.27 1.27))))
        )
        (pin bidirectional line (at 0 -25.4 0) (length 5.08)
          (name "PB105B" (effects (font (size 1.27 1.27))))
          (number "AJ31" (effects (font (size 1.27 1.27))))
        )
        (pin bidirectional line (at 0 -15.24 0) (length 5.08)
          (name "PB101B" (effects (font (size 1.27 1.27))))
          (number "AJ32" (effects (font (size 1.27 1.27))))
        )
        (pin bidirectional line (at 0 -7.62 0) (length 5.08)
          (name "PB98B" (effects (font (size 1.27 1.27))))
          (number "AK28" (effects (font (size 1.27 1.27))))
        )
        (pin bidirectional line (at 0 -43.18 0) (length 5.08)
          (name "PB116A" (effects (font (size 1.27 1.27))))
          (number "AK29" (effects (font (size 1.27 1.27))))
        )
        (pin bidirectional line (at 0 -48.26 0) (length 5.08)
          (name "PB116B" (effects (font (size 1.27 1.27))))
          (number "AK30" (effects (font (size 1.27 1.27))))
        )
        (pin bidirectional line (at 0 -20.32 0) (length 5.08)
          (name "PB105A" (effects (font (size 1.27 1.27))))
          (number "AK31" (effects (font (size 1.27 1.27))))
        )
        (pin bidirectional line (at 0 -10.16 0) (length 5.08)
          (name "PB101A" (effects (font (size 1.27 1.27))))
          (number "AK32" (effects (font (size 1.27 1.27))))
        )
        (pin bidirectional line (at 0 -2.54 0) (length 5.08)
          (name "PB98A" (effects (font (size 1.27 1.27))))
          (number "AL28" (effects (font (size 1.27 1.27))))
        )
        (pin bidirectional line (at 0 -17.78 0) (length 5.08)
          (name "PB103B" (effects (font (size 1.27 1.27))))
          (number "AL30" (effects (font (size 1.27 1.27))))
        )
        (pin bidirectional line (at 0 -27.94 0) (length 5.08)
          (name "PB107B" (effects (font (size 1.27 1.27))))
          (number "AL32" (effects (font (size 1.27 1.27))))
        )
        (pin bidirectional line (at 0 0 0) (length 5.08)
          (name "PB96A" (effects (font (size 1.27 1.27))))
          (number "AM28" (effects (font (size 1.27 1.27))))
        )
        (pin bidirectional line (at 0 -5.08 0) (length 5.08)
          (name "PB96B" (effects (font (size 1.27 1.27))))
          (number "AM29" (effects (font (size 1.27 1.27))))
        )
        (pin bidirectional line (at 0 -12.7 0) (length 5.08)
          (name "PB103A" (effects (font (size 1.27 1.27))))
          (number "AM30" (effects (font (size 1.27 1.27))))
        )
        (pin bidirectional line (at 0 -22.86 0) (length 5.08)
          (name "PB107A" (effects (font (size 1.27 1.27))))
          (number "AM31" (effects (font (size 1.27 1.27))))
        )
      )
      (symbol "ECP5_LFE5UM5G-85_7_1"
        (rectangle (start 5.08 2.54) (end 22.86 -162.56)
          (stroke (width 0.254) (type default))
          (fill (type background))
        )
        (pin power_in line (at 27.94 0 180) (length 5.08)
          (name "VCCIO6" (effects (font (size 1.27 1.27))))
          (number "AA10" (effects (font (size 1.27 1.27))))
        )
        (pin bidirectional line (at 0 -152.4 0) (length 5.08)
          (name "PL92A" (effects (font (size 1.27 1.27))))
          (number "AB1" (effects (font (size 1.27 1.27))))
        )
        (pin bidirectional line (at 0 -147.32 0) (length 5.08)
          (name "PL89B" (effects (font (size 1.27 1.27))))
          (number "AB2" (effects (font (size 1.27 1.27))))
        )
        (pin bidirectional line (at 0 -121.92 0) (length 5.08)
          (name "PL83A" (effects (font (size 1.27 1.27))))
          (number "AB3" (effects (font (size 1.27 1.27))))
        )
        (pin bidirectional line (at 0 -127 0) (length 5.08)
          (name "PL83B" (effects (font (size 1.27 1.27))))
          (number "AB4" (effects (font (size 1.27 1.27))))
        )
        (pin bidirectional line (at 0 -101.6 0) (length 5.08)
          (name "PL77A" (effects (font (size 1.27 1.27))))
          (number "AB5" (effects (font (size 1.27 1.27))))
        )
        (pin bidirectional line (at 0 -106.68 0) (length 5.08)
          (name "PL77B" (effects (font (size 1.27 1.27))))
          (number "AB6" (effects (font (size 1.27 1.27))))
        )
        (pin bidirectional line (at 0 -93.98 0) (length 5.08)
          (name "PL74C" (effects (font (size 1.27 1.27))))
          (number "AB7" (effects (font (size 1.27 1.27))))
        )
        (pin bidirectional line (at 0 -154.94 0) (length 5.08)
          (name "PL92B" (effects (font (size 1.27 1.27))))
          (number "AC1" (effects (font (size 1.27 1.27))))
        )
        (pin bidirectional line (at 0 -144.78 0) (length 5.08)
          (name "PL89C" (effects (font (size 1.27 1.27))))
          (number "AC2" (effects (font (size 1.27 1.27))))
        )
        (pin bidirectional line (at 0 -142.24 0) (length 5.08)
          (name "PL89A" (effects (font (size 1.27 1.27))))
          (number "AC3" (effects (font (size 1.27 1.27))))
        )
        (pin bidirectional line (at 0 -124.46 0) (length 5.08)
          (name "PL83C" (effects (font (size 1.27 1.27))))
          (number "AC5" (effects (font (size 1.27 1.27))))
        )
        (pin bidirectional line (at 0 -99.06 0) (length 5.08)
          (name "PL74D" (effects (font (size 1.27 1.27))))
          (number "AC6" (effects (font (size 1.27 1.27))))
        )
        (pin bidirectional line (at 0 -104.14 0) (length 5.08)
          (name "PL77C" (effects (font (size 1.27 1.27))))
          (number "AC7" (effects (font (size 1.27 1.27))))
        )
        (pin bidirectional line (at 0 -157.48 0) (length 5.08)
          (name "PL92C" (effects (font (size 1.27 1.27))))
          (number "AD1" (effects (font (size 1.27 1.27))))
        )
        (pin bidirectional line (at 0 -134.62 0) (length 5.08)
          (name "PL86C" (effects (font (size 1.27 1.27))))
          (number "AD3" (effects (font (size 1.27 1.27))))
        )
        (pin bidirectional line (at 0 -129.54 0) (length 5.08)
          (name "PL83D" (effects (font (size 1.27 1.27))))
          (number "AD4" (effects (font (size 1.27 1.27))))
        )
        (pin bidirectional line (at 0 -111.76 0) (length 5.08)
          (name "PL80A" (effects (font (size 1.27 1.27))))
          (number "AD6" (effects (font (size 1.27 1.27))))
        )
        (pin bidirectional line (at 0 -109.22 0) (length 5.08)
          (name "PL77D" (effects (font (size 1.27 1.27))))
          (number "AD7" (effects (font (size 1.27 1.27))))
        )
        (pin bidirectional line (at 0 -160.02 0) (length 5.08)
          (name "PL92D" (effects (font (size 1.27 1.27))))
          (number "AE1" (effects (font (size 1.27 1.27))))
        )
        (pin bidirectional line (at 0 -149.86 0) (length 5.08)
          (name "PL89D" (effects (font (size 1.27 1.27))))
          (number "AE2" (effects (font (size 1.27 1.27))))
        )
        (pin bidirectional line (at 0 -139.7 0) (length 5.08)
          (name "PL86D" (effects (font (size 1.27 1.27))))
          (number "AE3" (effects (font (size 1.27 1.27))))
        )
        (pin bidirectional line (at 0 -119.38 0) (length 5.08)
          (name "PL80D" (effects (font (size 1.27 1.27))))
          (number "AE4" (effects (font (size 1.27 1.27))))
        )
        (pin bidirectional line (at 0 -114.3 0) (length 5.08)
          (name "PL80C" (effects (font (size 1.27 1.27))))
          (number "AE5" (effects (font (size 1.27 1.27))))
        )
        (pin bidirectional line (at 0 -116.84 0) (length 5.08)
          (name "PL80B" (effects (font (size 1.27 1.27))))
          (number "AE6" (effects (font (size 1.27 1.27))))
        )
        (pin bidirectional line (at 0 -50.8 0) (length 5.08)
          (name "PL62A" (effects (font (size 1.27 1.27))))
          (number "N1" (effects (font (size 1.27 1.27))))
        )
        (pin bidirectional line (at 0 -55.88 0) (length 5.08)
          (name "PL62B" (effects (font (size 1.27 1.27))))
          (number "P1" (effects (font (size 1.27 1.27))))
        )
        (pin bidirectional line (at 0 -40.64 0) (length 5.08)
          (name "PL59A" (effects (font (size 1.27 1.27))))
          (number "P2" (effects (font (size 1.27 1.27))))
        )
        (pin bidirectional line (at 0 -45.72 0) (length 5.08)
          (name "PL59B" (effects (font (size 1.27 1.27))))
          (number "P3" (effects (font (size 1.27 1.27))))
        )
        (pin bidirectional line (at 0 -5.08 0) (length 5.08)
          (name "PL47B" (effects (font (size 1.27 1.27))))
          (number "P4" (effects (font (size 1.27 1.27))))
        )
        (pin bidirectional line (at 0 0 0) (length 5.08)
          (name "PL47A" (effects (font (size 1.27 1.27))))
          (number "P5" (effects (font (size 1.27 1.27))))
        )
        (pin bidirectional line (at 0 -60.96 0) (length 5.08)
          (name "PL65A" (effects (font (size 1.27 1.27))))
          (number "R1" (effects (font (size 1.27 1.27))))
        )
        (pin bidirectional line (at 0 -43.18 0) (length 5.08)
          (name "PL59C" (effects (font (size 1.27 1.27))))
          (number "R3" (effects (font (size 1.27 1.27))))
        )
        (pin bidirectional line (at 0 -20.32 0) (length 5.08)
          (name "PL53A" (effects (font (size 1.27 1.27))))
          (number "R4" (effects (font (size 1.27 1.27))))
        )
        (pin bidirectional line (at 0 -10.16 0) (length 5.08)
          (name "PL50A" (effects (font (size 1.27 1.27))))
          (number "R6" (effects (font (size 1.27 1.27))))
        )
        (pin bidirectional line (at 0 -2.54 0) (length 5.08)
          (name "PL47C" (effects (font (size 1.27 1.27))))
          (number "R7" (effects (font (size 1.27 1.27))))
        )
        (pin bidirectional line (at 0 -71.12 0) (length 5.08)
          (name "PL68A" (effects (font (size 1.27 1.27))))
          (number "T1" (effects (font (size 1.27 1.27))))
        )
        (pin bidirectional line (at 0 -66.04 0) (length 5.08)
          (name "PL65B" (effects (font (size 1.27 1.27))))
          (number "T2" (effects (font (size 1.27 1.27))))
        )
        (pin bidirectional line (at 0 -48.26 0) (length 5.08)
          (name "PL59D" (effects (font (size 1.27 1.27))))
          (number "T3" (effects (font (size 1.27 1.27))))
        )
        (pin bidirectional line (at 0 -22.86 0) (length 5.08)
          (name "PL53C" (effects (font (size 1.27 1.27))))
          (number "T4" (effects (font (size 1.27 1.27))))
        )
        (pin bidirectional line (at 0 -25.4 0) (length 5.08)
          (name "PL53B" (effects (font (size 1.27 1.27))))
          (number "T5" (effects (font (size 1.27 1.27))))
        )
        (pin bidirectional line (at 0 -15.24 0) (length 5.08)
          (name "PL50B" (effects (font (size 1.27 1.27))))
          (number "T6" (effects (font (size 1.27 1.27))))
        )
        (pin bidirectional line (at 0 -7.62 0) (length 5.08)
          (name "PL47D" (effects (font (size 1.27 1.27))))
          (number "T7" (effects (font (size 1.27 1.27))))
        )
        (pin bidirectional line (at 0 -76.2 0) (length 5.08)
          (name "PL68B" (effects (font (size 1.27 1.27))))
          (number "U1" (effects (font (size 1.27 1.27))))
        )
        (pin passive line (at 27.94 0 180) (length 5.08) hide
          (name "VCCIO6" (effects (font (size 1.27 1.27))))
          (number "U10" (effects (font (size 1.27 1.27))))
        )
        (pin bidirectional line (at 0 -53.34 0) (length 5.08)
          (name "PL62C" (effects (font (size 1.27 1.27))))
          (number "U2" (effects (font (size 1.27 1.27))))
        )
        (pin bidirectional line (at 0 -58.42 0) (length 5.08)
          (name "PL62D" (effects (font (size 1.27 1.27))))
          (number "U3" (effects (font (size 1.27 1.27))))
        )
        (pin bidirectional line (at 0 -30.48 0) (length 5.08)
          (name "PL56A" (effects (font (size 1.27 1.27))))
          (number "U4" (effects (font (size 1.27 1.27))))
        )
        (pin bidirectional line (at 0 -27.94 0) (length 5.08)
          (name "PL53D" (effects (font (size 1.27 1.27))))
          (number "U5" (effects (font (size 1.27 1.27))))
        )
        (pin bidirectional line (at 0 -12.7 0) (length 5.08)
          (name "PL50C" (effects (font (size 1.27 1.27))))
          (number "U6" (effects (font (size 1.27 1.27))))
        )
        (pin bidirectional line (at 0 -17.78 0) (length 5.08)
          (name "PL50D" (effects (font (size 1.27 1.27))))
          (number "U7" (effects (font (size 1.27 1.27))))
        )
        (pin bidirectional line (at 0 -73.66 0) (length 5.08)
          (name "PL68C" (effects (font (size 1.27 1.27))))
          (number "V1" (effects (font (size 1.27 1.27))))
        )
        (pin passive line (at 27.94 0 180) (length 5.08) hide
          (name "VCCIO6" (effects (font (size 1.27 1.27))))
          (number "V10" (effects (font (size 1.27 1.27))))
        )
        (pin bidirectional line (at 0 -35.56 0) (length 5.08)
          (name "PL56B" (effects (font (size 1.27 1.27))))
          (number "V4" (effects (font (size 1.27 1.27))))
        )
        (pin bidirectional line (at 0 -33.02 0) (length 5.08)
          (name "PL56C" (effects (font (size 1.27 1.27))))
          (number "V6" (effects (font (size 1.27 1.27))))
        )
        (pin bidirectional line (at 0 -38.1 0) (length 5.08)
          (name "PL56D" (effects (font (size 1.27 1.27))))
          (number "V7" (effects (font (size 1.27 1.27))))
        )
        (pin bidirectional line (at 0 -78.74 0) (length 5.08)
          (name "PL68D" (effects (font (size 1.27 1.27))))
          (number "W1" (effects (font (size 1.27 1.27))))
        )
        (pin passive line (at 27.94 0 180) (length 5.08) hide
          (name "VCCIO6" (effects (font (size 1.27 1.27))))
          (number "W10" (effects (font (size 1.27 1.27))))
        )
        (pin bidirectional line (at 0 -132.08 0) (length 5.08)
          (name "PL86A" (effects (font (size 1.27 1.27))))
          (number "W2" (effects (font (size 1.27 1.27))))
        )
        (pin bidirectional line (at 0 -63.5 0) (length 5.08)
          (name "PL65C" (effects (font (size 1.27 1.27))))
          (number "W3" (effects (font (size 1.27 1.27))))
        )
        (pin bidirectional line (at 0 -96.52 0) (length 5.08)
          (name "PL74B" (effects (font (size 1.27 1.27))))
          (number "W4" (effects (font (size 1.27 1.27))))
        )
        (pin bidirectional line (at 0 -88.9 0) (length 5.08)
          (name "PL71D" (effects (font (size 1.27 1.27))))
          (number "W5" (effects (font (size 1.27 1.27))))
        )
        (pin bidirectional line (at 0 -137.16 0) (length 5.08)
          (name "PL86B" (effects (font (size 1.27 1.27))))
          (number "Y1" (effects (font (size 1.27 1.27))))
        )
        (pin bidirectional line (at 0 -68.58 0) (length 5.08)
          (name "PL65D" (effects (font (size 1.27 1.27))))
          (number "Y3" (effects (font (size 1.27 1.27))))
        )
        (pin bidirectional line (at 0 -91.44 0) (length 5.08)
          (name "PL74A" (effects (font (size 1.27 1.27))))
          (number "Y4" (effects (font (size 1.27 1.27))))
        )
        (pin bidirectional line (at 0 -83.82 0) (length 5.08)
          (name "PL71C" (effects (font (size 1.27 1.27))))
          (number "Y5" (effects (font (size 1.27 1.27))))
        )
        (pin bidirectional line (at 0 -86.36 0) (length 5.08)
          (name "PL71B" (effects (font (size 1.27 1.27))))
          (number "Y6" (effects (font (size 1.27 1.27))))
        )
        (pin bidirectional line (at 0 -81.28 0) (length 5.08)
          (name "PL71A" (effects (font (size 1.27 1.27))))
          (number "Y7" (effects (font (size 1.27 1.27))))
        )
      )
      (symbol "ECP5_LFE5UM5G-85_8_1"
        (rectangle (start 5.08 2.54) (end 22.86 -121.92)
          (stroke (width 0.254) (type default))
          (fill (type background))
        )
        (pin bidirectional line (at 0 -20.32 0) (length 5.08)
          (name "PL17A" (effects (font (size 1.27 1.27))))
          (number "B1" (effects (font (size 1.27 1.27))))
        )
        (pin bidirectional line (at 0 -33.02 0) (length 5.08)
          (name "PL20C" (effects (font (size 1.27 1.27))))
          (number "C1" (effects (font (size 1.27 1.27))))
        )
        (pin bidirectional line (at 0 -25.4 0) (length 5.08)
          (name "PL17B" (effects (font (size 1.27 1.27))))
          (number "C2" (effects (font (size 1.27 1.27))))
        )
        (pin bidirectional line (at 0 -7.62 0) (length 5.08)
          (name "PL11D" (effects (font (size 1.27 1.27))))
          (number "C3" (effects (font (size 1.27 1.27))))
        )
        (pin bidirectional line (at 0 -5.08 0) (length 5.08)
          (name "PL11C" (effects (font (size 1.27 1.27))))
          (number "C4" (effects (font (size 1.27 1.27))))
        )
        (pin bidirectional line (at 0 0 0) (length 5.08)
          (name "PL11A" (effects (font (size 1.27 1.27))))
          (number "C5" (effects (font (size 1.27 1.27))))
        )
        (pin bidirectional line (at 0 -38.1 0) (length 5.08)
          (name "PL20D" (effects (font (size 1.27 1.27))))
          (number "D1" (effects (font (size 1.27 1.27))))
        )
        (pin bidirectional line (at 0 -27.94 0) (length 5.08)
          (name "PL17D" (effects (font (size 1.27 1.27))))
          (number "D2" (effects (font (size 1.27 1.27))))
        )
        (pin bidirectional line (at 0 -22.86 0) (length 5.08)
          (name "PL17C" (effects (font (size 1.27 1.27))))
          (number "D3" (effects (font (size 1.27 1.27))))
        )
        (pin bidirectional line (at 0 -10.16 0) (length 5.08)
          (name "PL14A" (effects (font (size 1.27 1.27))))
          (number "D4" (effects (font (size 1.27 1.27))))
        )
        (pin bidirectional line (at 0 -2.54 0) (length 5.08)
          (name "PL11B" (effects (font (size 1.27 1.27))))
          (number "D5" (effects (font (size 1.27 1.27))))
        )
        (pin bidirectional line (at 0 -45.72 0) (length 5.08)
          (name "PL23B" (effects (font (size 1.27 1.27))))
          (number "E1" (effects (font (size 1.27 1.27))))
        )
        (pin bidirectional line (at 0 -35.56 0) (length 5.08)
          (name "PL20B" (effects (font (size 1.27 1.27))))
          (number "E3" (effects (font (size 1.27 1.27))))
        )
        (pin bidirectional line (at 0 -15.24 0) (length 5.08)
          (name "PL14B" (effects (font (size 1.27 1.27))))
          (number "E4" (effects (font (size 1.27 1.27))))
        )
        (pin bidirectional line (at 0 -43.18 0) (length 5.08)
          (name "PL23C" (effects (font (size 1.27 1.27))))
          (number "F1" (effects (font (size 1.27 1.27))))
        )
        (pin bidirectional line (at 0 -40.64 0) (length 5.08)
          (name "PL23A" (effects (font (size 1.27 1.27))))
          (number "F2" (effects (font (size 1.27 1.27))))
        )
        (pin bidirectional line (at 0 -30.48 0) (length 5.08)
          (name "PL20A" (effects (font (size 1.27 1.27))))
          (number "F3" (effects (font (size 1.27 1.27))))
        )
        (pin bidirectional line (at 0 -12.7 0) (length 5.08)
          (name "PL14C" (effects (font (size 1.27 1.27))))
          (number "F4" (effects (font (size 1.27 1.27))))
        )
        (pin bidirectional line (at 0 -17.78 0) (length 5.08)
          (name "PL14D" (effects (font (size 1.27 1.27))))
          (number "F5" (effects (font (size 1.27 1.27))))
        )
        (pin bidirectional line (at 0 -48.26 0) (length 5.08)
          (name "PL23D" (effects (font (size 1.27 1.27))))
          (number "H1" (effects (font (size 1.27 1.27))))
        )
        (pin bidirectional line (at 0 -50.8 0) (length 5.08)
          (name "PL26A" (effects (font (size 1.27 1.27))))
          (number "H2" (effects (font (size 1.27 1.27))))
        )
        (pin bidirectional line (at 0 -55.88 0) (length 5.08)
          (name "PL26B" (effects (font (size 1.27 1.27))))
          (number "H3" (effects (font (size 1.27 1.27))))
        )
        (pin bidirectional line (at 0 -86.36 0) (length 5.08)
          (name "PL35B" (effects (font (size 1.27 1.27))))
          (number "H5" (effects (font (size 1.27 1.27))))
        )
        (pin bidirectional line (at 0 -81.28 0) (length 5.08)
          (name "PL35A" (effects (font (size 1.27 1.27))))
          (number "H6" (effects (font (size 1.27 1.27))))
        )
        (pin bidirectional line (at 0 -66.04 0) (length 5.08)
          (name "PL29B" (effects (font (size 1.27 1.27))))
          (number "J1" (effects (font (size 1.27 1.27))))
        )
        (pin bidirectional line (at 0 -53.34 0) (length 5.08)
          (name "PL26C" (effects (font (size 1.27 1.27))))
          (number "J3" (effects (font (size 1.27 1.27))))
        )
        (pin bidirectional line (at 0 -73.66 0) (length 5.08)
          (name "PL32C" (effects (font (size 1.27 1.27))))
          (number "J4" (effects (font (size 1.27 1.27))))
        )
        (pin bidirectional line (at 0 -88.9 0) (length 5.08)
          (name "PL35D" (effects (font (size 1.27 1.27))))
          (number "J6" (effects (font (size 1.27 1.27))))
        )
        (pin bidirectional line (at 0 -83.82 0) (length 5.08)
          (name "PL35C" (effects (font (size 1.27 1.27))))
          (number "J7" (effects (font (size 1.27 1.27))))
        )
        (pin bidirectional line (at 0 -63.5 0) (length 5.08)
          (name "PL29C" (effects (font (size 1.27 1.27))))
          (number "K1" (effects (font (size 1.27 1.27))))
        )
        (pin bidirectional line (at 0 -60.96 0) (length 5.08)
          (name "PL29A" (effects (font (size 1.27 1.27))))
          (number "K2" (effects (font (size 1.27 1.27))))
        )
        (pin bidirectional line (at 0 -58.42 0) (length 5.08)
          (name "PL26D" (effects (font (size 1.27 1.27))))
          (number "K3" (effects (font (size 1.27 1.27))))
        )
        (pin bidirectional line (at 0 -78.74 0) (length 5.08)
          (name "PL32D" (effects (font (size 1.27 1.27))))
          (number "K4" (effects (font (size 1.27 1.27))))
        )
        (pin bidirectional line (at 0 -93.98 0) (length 5.08)
          (name "PL38C" (effects (font (size 1.27 1.27))))
          (number "K5" (effects (font (size 1.27 1.27))))
        )
        (pin bidirectional line (at 0 -91.44 0) (length 5.08)
          (name "PL38A" (effects (font (size 1.27 1.27))))
          (number "K6" (effects (font (size 1.27 1.27))))
        )
        (pin bidirectional line (at 0 -96.52 0) (length 5.08)
          (name "PL38B" (effects (font (size 1.27 1.27))))
          (number "K7" (effects (font (size 1.27 1.27))))
        )
        (pin bidirectional line (at 0 -68.58 0) (length 5.08)
          (name "PL29D" (effects (font (size 1.27 1.27))))
          (number "L1" (effects (font (size 1.27 1.27))))
        )
        (pin bidirectional line (at 0 -71.12 0) (length 5.08)
          (name "PL32A" (effects (font (size 1.27 1.27))))
          (number "L2" (effects (font (size 1.27 1.27))))
        )
        (pin bidirectional line (at 0 -76.2 0) (length 5.08)
          (name "PL32B" (effects (font (size 1.27 1.27))))
          (number "L3" (effects (font (size 1.27 1.27))))
        )
        (pin bidirectional line (at 0 -99.06 0) (length 5.08)
          (name "PL38D" (effects (font (size 1.27 1.27))))
          (number "L4" (effects (font (size 1.27 1.27))))
        )
        (pin bidirectional line (at 0 -109.22 0) (length 5.08)
          (name "PL41D" (effects (font (size 1.27 1.27))))
          (number "L6" (effects (font (size 1.27 1.27))))
        )
        (pin bidirectional line (at 0 -104.14 0) (length 5.08)
          (name "PL41C" (effects (font (size 1.27 1.27))))
          (number "L7" (effects (font (size 1.27 1.27))))
        )
        (pin power_in line (at 27.94 0 180) (length 5.08)
          (name "VCCIO7" (effects (font (size 1.27 1.27))))
          (number "M10" (effects (font (size 1.27 1.27))))
        )
        (pin bidirectional line (at 0 -101.6 0) (length 5.08)
          (name "PL41A" (effects (font (size 1.27 1.27))))
          (number "N3" (effects (font (size 1.27 1.27))))
        )
        (pin bidirectional line (at 0 -106.68 0) (length 5.08)
          (name "PL41B" (effects (font (size 1.27 1.27))))
          (number "N4" (effects (font (size 1.27 1.27))))
        )
        (pin bidirectional line (at 0 -111.76 0) (length 5.08)
          (name "PL44A" (effects (font (size 1.27 1.27))))
          (number "N6" (effects (font (size 1.27 1.27))))
        )
        (pin bidirectional line (at 0 -116.84 0) (length 5.08)
          (name "PL44B" (effects (font (size 1.27 1.27))))
          (number "N7" (effects (font (size 1.27 1.27))))
        )
        (pin passive line (at 27.94 0 180) (length 5.08) hide
          (name "VCCIO7" (effects (font (size 1.27 1.27))))
          (number "P10" (effects (font (size 1.27 1.27))))
        )
        (pin bidirectional line (at 0 -114.3 0) (length 5.08)
          (name "PL44C" (effects (font (size 1.27 1.27))))
          (number "P6" (effects (font (size 1.27 1.27))))
        )
        (pin bidirectional line (at 0 -119.38 0) (length 5.08)
          (name "PL44D" (effects (font (size 1.27 1.27))))
          (number "P7" (effects (font (size 1.27 1.27))))
        )
        (pin passive line (at 27.94 0 180) (length 5.08) hide
          (name "VCCIO7" (effects (font (size 1.27 1.27))))
          (number "R10" (effects (font (size 1.27 1.27))))
        )
        (pin passive line (at 27.94 0 180) (length 5.08) hide
          (name "VCCIO7" (effects (font (size 1.27 1.27))))
          (number "T10" (effects (font (size 1.27 1.27))))
        )
      )
      (symbol "ECP5_LFE5UM5G-85_9_1"
        (rectangle (start 5.08 2.54) (end 20.32 -50.8)
          (stroke (width 0.254) (type default))
          (fill (type background))
        )
        (pin power_in line (at 25.4 0 180) (length 5.08)
          (name "VCCIO8" (effects (font (size 1.27 1.27))))
          (number "AB10" (effects (font (size 1.27 1.27))))
        )
        (pin passive line (at 25.4 0 180) (length 5.08) hide
          (name "VCCIO8" (effects (font (size 1.27 1.27))))
          (number "AC10" (effects (font (size 1.27 1.27))))
        )
        (pin bidirectional line (at 0 0 0) (length 5.08)
          (name "PB4A" (effects (font (size 1.27 1.27))))
          (number "AG1" (effects (font (size 1.27 1.27))))
        )
        (pin bidirectional line (at 0 -20.32 0) (length 5.08)
          (name "PB13A" (effects (font (size 1.27 1.27))))
          (number "AG3" (effects (font (size 1.27 1.27))))
        )
        (pin bidirectional line (at 0 -33.02 0) (length 5.08)
          (name "INITN" (effects (font (size 1.27 1.27))))
          (number "AG4" (effects (font (size 1.27 1.27))))
        )
        (pin bidirectional line (at 0 -5.08 0) (length 5.08)
          (name "PB4B" (effects (font (size 1.27 1.27))))
          (number "AH1" (effects (font (size 1.27 1.27))))
        )
        (pin bidirectional line (at 0 -25.4 0) (length 5.08)
          (name "PB13B" (effects (font (size 1.27 1.27))))
          (number "AH3" (effects (font (size 1.27 1.27))))
        )
        (pin bidirectional line (at 0 -38.1 0) (length 5.08)
          (name "PROGRAMN" (effects (font (size 1.27 1.27))))
          (number "AH4" (effects (font (size 1.27 1.27))))
        )
        (pin bidirectional line (at 0 -2.54 0) (length 5.08)
          (name "PB6A" (effects (font (size 1.27 1.27))))
          (number "AJ1" (effects (font (size 1.27 1.27))))
        )
        (pin bidirectional line (at 0 -12.7 0) (length 5.08)
          (name "PB11A" (effects (font (size 1.27 1.27))))
          (number "AJ2" (effects (font (size 1.27 1.27))))
        )
        (pin bidirectional line (at 0 -22.86 0) (length 5.08)
          (name "PB15A" (effects (font (size 1.27 1.27))))
          (number "AJ3" (effects (font (size 1.27 1.27))))
        )
        (pin bidirectional line (at 0 -40.64 0) (length 5.08)
          (name "DONE" (effects (font (size 1.27 1.27))))
          (number "AJ4" (effects (font (size 1.27 1.27))))
        )
        (pin bidirectional line (at 0 -7.62 0) (length 5.08)
          (name "PB6B" (effects (font (size 1.27 1.27))))
          (number "AK1" (effects (font (size 1.27 1.27))))
        )
        (pin bidirectional line (at 0 -17.78 0) (length 5.08)
          (name "PB11B" (effects (font (size 1.27 1.27))))
          (number "AK2" (effects (font (size 1.27 1.27))))
        )
        (pin bidirectional line (at 0 -27.94 0) (length 5.08)
          (name "PB15B" (effects (font (size 1.27 1.27))))
          (number "AK3" (effects (font (size 1.27 1.27))))
        )
        (pin bidirectional line (at 0 -45.72 0) (length 5.08)
          (name "CFG_2" (effects (font (size 1.27 1.27))))
          (number "AK4" (effects (font (size 1.27 1.27))))
        )
        (pin bidirectional line (at 0 -10.16 0) (length 5.08)
          (name "PB9A" (effects (font (size 1.27 1.27))))
          (number "AL1" (effects (font (size 1.27 1.27))))
        )
        (pin bidirectional line (at 0 -30.48 0) (length 5.08)
          (name "PB18A" (effects (font (size 1.27 1.27))))
          (number "AL3" (effects (font (size 1.27 1.27))))
        )
        (pin bidirectional line (at 0 -43.18 0) (length 5.08)
          (name "CFG_1" (effects (font (size 1.27 1.27))))
          (number "AL4" (effects (font (size 1.27 1.27))))
        )
        (pin bidirectional line (at 0 -15.24 0) (length 5.08)
          (name "PB9B" (effects (font (size 1.27 1.27))))
          (number "AM2" (effects (font (size 1.27 1.27))))
        )
        (pin bidirectional line (at 0 -35.56 0) (length 5.08)
          (name "CCLK" (effects (font (size 1.27 1.27))))
          (number "AM3" (effects (font (size 1.27 1.27))))
        )
        (pin bidirectional line (at 0 -48.26 0) (length 5.08)
          (name "CFG_0" (effects (font (size 1.27 1.27))))
          (number "AM4" (effects (font (size 1.27 1.27))))
        )
      )
      (symbol "ECP5_LFE5UM5G-85_10_1"
        (rectangle (start 5.08 2.54) (end 12.7 -10.16)
          (stroke (width 0.254) (type default))
          (fill (type background))
        )
        (pin bidirectional line (at 0 0 0) (length 5.08)
          (name "TDO" (effects (font (size 1.27 1.27))))
          (number "AG5" (effects (font (size 1.27 1.27))))
        )
        (pin bidirectional line (at 0 -5.08 0) (length 5.08)
          (name "TDI" (effects (font (size 1.27 1.27))))
          (number "AJ5" (effects (font (size 1.27 1.27))))
        )
        (pin bidirectional line (at 0 -2.54 0) (length 5.08)
          (name "TCK" (effects (font (size 1.27 1.27))))
          (number "AK5" (effects (font (size 1.27 1.27))))
        )
        (pin bidirectional line (at 0 -7.62 0) (length 5.08)
          (name "TMS" (effects (font (size 1.27 1.27))))
          (number "AM5" (effects (font (size 1.27 1.27))))
        )
      )
      (symbol "ECP5_LFE5UM5G-85_11_1"
        (rectangle (start 5.08 2.54) (end 22.86 -25.4)
          (stroke (width 0.254) (type default))
          (fill (type background))
        )
        (pin bidirectional line (at 0 -2.54 0) (length 5.08)
          (name "HDTXN0_D0CH0" (effects (font (size 1.27 1.27))))
          (number "AK10" (effects (font (size 1.27 1.27))))
        )
        (pin bidirectional line (at 0 -15.24 0) (length 5.08)
          (name "HDTXP0_D0CH1" (effects (font (size 1.27 1.27))))
          (number "AK12" (effects (font (size 1.27 1.27))))
        )
        (pin bidirectional line (at 0 -17.78 0) (length 5.08)
          (name "HDTXN0_D0CH1" (effects (font (size 1.27 1.27))))
          (number "AK13" (effects (font (size 1.27 1.27))))
        )
        (pin bidirectional line (at 0 0 0) (length 5.08)
          (name "HDTXP0_D0CH0" (effects (font (size 1.27 1.27))))
          (number "AK9" (effects (font (size 1.27 1.27))))
        )
        (pin bidirectional line (at 0 -10.16 0) (length 5.08)
          (name "HDRXP0_D0CH1" (effects (font (size 1.27 1.27))))
          (number "AM11" (effects (font (size 1.27 1.27))))
        )
        (pin bidirectional line (at 0 -12.7 0) (length 5.08)
          (name "HDRXN0_D0CH1" (effects (font (size 1.27 1.27))))
          (number "AM12" (effects (font (size 1.27 1.27))))
        )
        (pin bidirectional line (at 0 -20.32 0) (length 5.08)
          (name "REFCLKP_D0" (effects (font (size 1.27 1.27))))
          (number "AM14" (effects (font (size 1.27 1.27))))
        )
        (pin bidirectional line (at 0 -22.86 0) (length 5.08)
          (name "REFCLKN_D0" (effects (font (size 1.27 1.27))))
          (number "AM15" (effects (font (size 1.27 1.27))))
        )
        (pin bidirectional line (at 0 -5.08 0) (length 5.08)
          (name "HDRXP0_D0CH0" (effects (font (size 1.27 1.27))))
          (number "AM8" (effects (font (size 1.27 1.27))))
        )
        (pin bidirectional line (at 0 -7.62 0) (length 5.08)
          (name "HDRXN0_D0CH0" (effects (font (size 1.27 1.27))))
          (number "AM9" (effects (font (size 1.27 1.27))))
        )
      )
      (symbol "ECP5_LFE5UM5G-85_12_1"
        (rectangle (start 5.08 2.54) (end 22.86 -25.4)
          (stroke (width 0.254) (type default))
          (fill (type background))
        )
        (pin bidirectional line (at 0 0 0) (length 5.08)
          (name "HDTXP0_D1CH0" (effects (font (size 1.27 1.27))))
          (number "AK18" (effects (font (size 1.27 1.27))))
        )
        (pin bidirectional line (at 0 -2.54 0) (length 5.08)
          (name "HDTXN0_D1CH0" (effects (font (size 1.27 1.27))))
          (number "AK19" (effects (font (size 1.27 1.27))))
        )
        (pin bidirectional line (at 0 -15.24 0) (length 5.08)
          (name "HDTXP0_D1CH1" (effects (font (size 1.27 1.27))))
          (number "AK21" (effects (font (size 1.27 1.27))))
        )
        (pin bidirectional line (at 0 -17.78 0) (length 5.08)
          (name "HDTXN0_D1CH1" (effects (font (size 1.27 1.27))))
          (number "AK22" (effects (font (size 1.27 1.27))))
        )
        (pin bidirectional line (at 0 -5.08 0) (length 5.08)
          (name "HDRXP0_D1CH0" (effects (font (size 1.27 1.27))))
          (number "AM17" (effects (font (size 1.27 1.27))))
        )
        (pin bidirectional line (at 0 -7.62 0) (length 5.08)
          (name "HDRXN0_D1CH0" (effects (font (size 1.27 1.27))))
          (number "AM18" (effects (font (size 1.27 1.27))))
        )
        (pin bidirectional line (at 0 -10.16 0) (length 5.08)
          (name "HDRXP0_D1CH1" (effects (font (size 1.27 1.27))))
          (number "AM20" (effects (font (size 1.27 1.27))))
        )
        (pin bidirectional line (at 0 -12.7 0) (length 5.08)
          (name "HDRXN0_D1CH1" (effects (font (size 1.27 1.27))))
          (number "AM21" (effects (font (size 1.27 1.27))))
        )
        (pin bidirectional line (at 0 -20.32 0) (length 5.08)
          (name "REFCLKP_D1" (effects (font (size 1.27 1.27))))
          (number "AM23" (effects (font (size 1.27 1.27))))
        )
        (pin bidirectional line (at 0 -22.86 0) (length 5.08)
          (name "REFCLKN_D1" (effects (font (size 1.27 1.27))))
          (number "AM24" (effects (font (size 1.27 1.27))))
        )
      )
    )
	(symbol "antmicroFerriteBeadsandChips:FB_120Z_2A_Murata-BLM18PG_0603" (pin_numbers hide) (pin_names hide) (in_bom yes) (on_board yes)
      (property "Reference" "FB" (at 15.24 0 0)
        (effects (font (size 1.27 1.27) (thickness 0.15)) (justify left bottom))
      )
      (property "Value" "FB_120Z_2A_Murata-BLM18PG_0603" (at 15.24 -2.54 0)
        (effects (font (size 1.27 1.27) (thickness 0.15)) (justify left bottom) hide)
      )
      (property "Footprint" "antmicro-footprints:FB_0603_1608Metric" (at 15.24 -7.62 0)
        (effects (font (size 1.27 1.27) (thickness 0.15)) (justify left bottom) hide)
      )
      (property "Datasheet" "https://www.murata.com/en-us/products/productdata/8796738650142/ENFA0003.pdf" (at 15.24 -10.16 0)
        (effects (font (size 1.27 1.27) (thickness 0.15)) (justify left bottom) hide)
      )
      (property "Val" "120Z/2A" (at 15.24 -5.08 0)
        (effects (font (size 1.27 1.27)) (justify left bottom))
      )
      (property "MPN" "BLM18PG121SN1D" (at 15.24 -12.7 0)
        (effects (font (size 1.27 1.27) (thickness 0.15)) (justify left bottom) hide)
      )
      (property "Manufacturer" "Murata" (at 15.24 -15.24 0)
        (effects (font (size 1.27 1.27) (thickness 0.15)) (justify left bottom) hide)
      )
      (property "Current" "" (at 20.32 -22.86 0)
        (effects (font (size 1.27 1.27) (thickness 0.15)) (justify left bottom) hide)
      )
      (property "Author" "Antmicro" (at 15.24 -17.78 0)
        (effects (font (size 1.27 1.27) (thickness 0.15)) (justify left bottom) hide)
      )
      (property "License" "Apache-2.0" (at 15.24 -20.32 0)
        (effects (font (size 1.27 1.27) (thickness 0.15)) (justify left bottom) hide)
      )
      (property "ki_keywords" "0603, SMT, FERRITE BEAD, PASSIVE" (at 0 0 0)
        (effects (font (size 1.27 1.27)) hide)
      )
      (property "ki_description" "Ferrite Bead, 0603 [1608 Metric], 120 ohm, 2 A, BLM18P, 0.05 ohm, ± 25%, DC power line" (at 0 0 0)
        (effects (font (size 1.27 1.27)) hide)
      )
      (symbol "FB_120Z_2A_Murata-BLM18PG_0603_0_1"
        (polyline
          (pts
            (xy 1.651 0)
            (xy 1.2446 0)
          )
          (stroke (width 0) (type default))
          (fill (type none))
        )
        (polyline
          (pts
            (xy 3.81 0)
            (xy 3.3274 0)
          )
          (stroke (width 0) (type default))
          (fill (type none))
        )
        (polyline
          (pts
            (xy 2.2606 -1.8288)
            (xy 1.0414 -1.1176)
            (xy 2.7432 1.8288)
            (xy 3.9624 1.1176)
            (xy 2.2606 -1.8288)
          )
          (stroke (width 0) (type default))
          (fill (type none))
        )
      )
      (symbol "FB_120Z_2A_Murata-BLM18PG_0603_1_1"
        (pin passive line (at 0 0 0) (length 1.27)
          (name "~" (effects (font (size 1.27 1.27))))
          (number "1" (effects (font (size 1.27 1.27))))
        )
        (pin passive line (at 5.08 0 180) (length 1.27)
          (name "~" (effects (font (size 1.27 1.27))))
          (number "2" (effects (font (size 1.27 1.27))))
        )
      )
    )
	(symbol "antmicroFerriteBeadsandChips:FB_600Z_0.3A_Murata-BLM15AG_0402" (pin_numbers hide) (pin_names hide) (in_bom yes) (on_board yes)
      (property "Reference" "FB" (at 15.24 0 0)
        (effects (font (size 1.27 1.27) (thickness 0.15)) (justify left bottom))
      )
      (property "Value" "FB_600Z_0.3A_Murata-BLM15AG_0402" (at 15.24 -2.54 0)
        (effects (font (size 1.27 1.27) (thickness 0.15)) (justify left bottom) hide)
      )
      (property "Footprint" "antmicro-footprints:FB_0402_1005Metric" (at 15.24 -7.62 0)
        (effects (font (size 1.27 1.27) (thickness 0.15)) (justify left bottom) hide)
      )
      (property "Datasheet" "https://www.murata.com/en-us/products/productdata/8796740059166/ENFA0018.pdf" (at 15.24 -10.16 0)
        (effects (font (size 1.27 1.27) (thickness 0.15)) (justify left bottom) hide)
      )
      (property "Val" "600Z/0.3A" (at 15.24 -5.08 0)
        (effects (font (size 1.27 1.27)) (justify left bottom))
      )
      (property "MPN" "BLM15AG601SN1D" (at 15.24 -12.7 0)
        (effects (font (size 1.27 1.27) (thickness 0.15)) (justify left bottom) hide)
      )
      (property "Manufacturer" "Murata" (at 15.24 -15.24 0)
        (effects (font (size 1.27 1.27) (thickness 0.15)) (justify left bottom) hide)
      )
      (property "Current" "" (at 20.32 -22.86 0)
        (effects (font (size 1.27 1.27) (thickness 0.15)) (justify left bottom) hide)
      )
      (property "Author" "Antmicro" (at 15.24 -17.78 0)
        (effects (font (size 1.27 1.27) (thickness 0.15)) (justify left bottom) hide)
      )
      (property "License" "Apache-2.0" (at 15.24 -20.32 0)
        (effects (font (size 1.27 1.27) (thickness 0.15)) (justify left bottom) hide)
      )
      (property "ki_keywords" "0402, SMT, FERRITE BEAD, PASSIVE" (at 0 0 0)
        (effects (font (size 1.27 1.27)) hide)
      )
      (property "ki_description" "Ferrite Bead, 0402 [1005 Metric], 600 ohm, 300 mA, BLM15AG_SN, 0.6 ohm, ± 25%, General use" (at 0 0 0)
        (effects (font (size 1.27 1.27)) hide)
      )
      (symbol "FB_600Z_0.3A_Murata-BLM15AG_0402_0_1"
        (polyline
          (pts
            (xy 1.651 0)
            (xy 1.2446 0)
          )
          (stroke (width 0) (type default))
          (fill (type none))
        )
        (polyline
          (pts
            (xy 3.81 0)
            (xy 3.3274 0)
          )
          (stroke (width 0) (type default))
          (fill (type none))
        )
        (polyline
          (pts
            (xy 2.2606 -1.8288)
            (xy 1.0414 -1.1176)
            (xy 2.7432 1.8288)
            (xy 3.9624 1.1176)
            (xy 2.2606 -1.8288)
          )
          (stroke (width 0) (type default))
          (fill (type none))
        )
      )
      (symbol "FB_600Z_0.3A_Murata-BLM15AG_0402_1_1"
        (pin passive line (at 0 0 0) (length 1.27)
          (name "~" (effects (font (size 1.27 1.27))))
          (number "1" (effects (font (size 1.27 1.27))))
        )
        (pin passive line (at 5.08 0 180) (length 1.27)
          (name "~" (effects (font (size 1.27 1.27))))
          (number "2" (effects (font (size 1.27 1.27))))
        )
      )
    )
	(symbol "antmicroFixedInductors:L_470n_6.7A_Vishay-IHLP-1212AE-11" (pin_numbers hide) (pin_names hide) (in_bom yes) (on_board yes)
      (property "Reference" "L" (at 13.97 0 0)
        (effects (font (size 1.27 1.27) (thickness 0.15)) (justify left bottom))
      )
      (property "Value" "L_470n_6.7A_Vishay-IHLP-1212AE-11" (at 13.97 -2.54 0)
        (effects (font (size 1.27 1.27) (thickness 0.15)) (justify left bottom) hide)
      )
      (property "Footprint" "antmicro-footprints:L_Vishay-IHLP-1212AE" (at 13.97 -7.62 0)
        (effects (font (size 1.27 1.27) (thickness 0.15)) (justify left bottom) hide)
      )
      (property "Datasheet" "https://www.vishay.com/docs/34300/ihlp-1212ae-11.pdf" (at 13.97 -10.16 0)
        (effects (font (size 1.27 1.27) (thickness 0.15)) (justify left bottom) hide)
      )
      (property "Val" "470n/6.7A" (at 13.97 -5.08 0)
        (effects (font (size 1.27 1.27) (thickness 0.15)) (justify left bottom))
      )
      (property "Manufacturer" "Vishay" (at 13.97 -12.7 0)
        (effects (font (size 1.27 1.27) (thickness 0.15)) (justify left bottom) hide)
      )
      (property "MPN" "IHLP1212AEERR47M11" (at 13.97 -15.24 0)
        (effects (font (size 1.27 1.27) (thickness 0.15)) (justify left bottom) hide)
      )
      (property "ISat" "6.7 A" (at 13.97 -16.51 0)
        (effects (font (size 1.27 1.27)) (justify left) hide)
      )
      (property "IMax" "6.7 A" (at 13.97 -20.32 0)
        (effects (font (size 1.27 1.27) (thickness 0.15)) (justify left bottom) hide)
      )
      (property "Size" "3.0x3.0" (at 13.97 -22.86 0)
        (effects (font (size 1.27 1.27) (thickness 0.15)) (justify left bottom) hide)
      )
      (property "Author" "Antmicro" (at 13.97 -25.4 0)
        (effects (font (size 1.27 1.27) (thickness 0.15)) (justify left bottom) hide)
      )
      (property "License" "Apache-2.0" (at 13.97 -27.94 0)
        (effects (font (size 1.27 1.27) (thickness 0.15)) (justify left bottom) hide)
      )
      (property "ki_keywords" "SMT, INDUCTOR, PASSIVE" (at 0 0 0)
        (effects (font (size 1.27 1.27)) hide)
      )
      (property "ki_description" "Power Inductor (SMT), 470 nH, 6.7 A, Shielded, 6.7 A" (at 0 0 0)
        (effects (font (size 1.27 1.27)) hide)
      )
      (symbol "L_470n_6.7A_Vishay-IHLP-1212AE-11_0_1"
        (arc (start 1.524 0) (mid 1.016 0.5058) (end 0.508 0)
          (stroke (width 0) (type default))
          (fill (type none))
        )
        (arc (start 2.54 0) (mid 2.032 0.5058) (end 1.524 0)
          (stroke (width 0) (type default))
          (fill (type none))
        )
        (arc (start 3.556 0) (mid 3.048 0.5058) (end 2.54 0)
          (stroke (width 0) (type default))
          (fill (type none))
        )
        (arc (start 4.572 0) (mid 4.064 0.5058) (end 3.556 0)
          (stroke (width 0) (type default))
          (fill (type none))
        )
      )
      (symbol "L_470n_6.7A_Vishay-IHLP-1212AE-11_1_1"
        (pin passive line (at 0 0 0) (length 0.508)
          (name "~" (effects (font (size 1.27 1.27))))
          (number "1" (effects (font (size 1.27 1.27))))
        )
        (pin passive line (at 5.08 0 180) (length 0.508)
          (name "~" (effects (font (size 1.27 1.27))))
          (number "2" (effects (font (size 1.27 1.27))))
        )
      )
    )
	(symbol "antmicroFixedInductors:L_7u2_7.9A_WE-PDF-1064" (pin_numbers hide) (pin_names hide) (in_bom yes) (on_board yes)
      (property "Reference" "L" (at 13.97 0 0)
        (effects (font (size 1.27 1.27) (thickness 0.15)) (justify left bottom))
      )
      (property "Value" "L_7u2_7.9A_WE-PDF-1064" (at 13.97 -2.54 0)
        (effects (font (size 1.27 1.27) (thickness 0.15)) (justify left bottom) hide)
      )
      (property "Footprint" "antmicro-footprints:L_WE-PDF-1064" (at 13.97 -7.62 0)
        (effects (font (size 1.27 1.27) (thickness 0.15)) (justify left bottom) hide)
      )
      (property "Datasheet" "https://www.we-online.com/catalog/datasheet/7447798720.pdf" (at 13.97 -10.16 0)
        (effects (font (size 1.27 1.27) (thickness 0.15)) (justify left bottom) hide)
      )
      (property "Val" "7u2/7.9A" (at 13.97 -5.08 0)
        (effects (font (size 1.27 1.27) (thickness 0.15)) (justify left bottom))
      )
      (property "Manufacturer" "Würth Elektronik" (at 13.97 -12.7 0)
        (effects (font (size 1.27 1.27) (thickness 0.15)) (justify left bottom) hide)
      )
      (property "MPN" "7447798720" (at 13.97 -15.24 0)
        (effects (font (size 1.27 1.27) (thickness 0.15)) (justify left bottom) hide)
      )
      (property "ISat" "6 A" (at 13.97 -16.51 0)
        (effects (font (size 1.27 1.27)) (justify left) hide)
      )
      (property "IMax" "7.9 A" (at 13.97 -20.32 0)
        (effects (font (size 1.27 1.27) (thickness 0.15)) (justify left bottom) hide)
      )
      (property "Size" "10.2x10.2" (at 13.97 -22.86 0)
        (effects (font (size 1.27 1.27) (thickness 0.15)) (justify left bottom) hide)
      )
      (property "Author" "Antmicro" (at 13.97 -25.4 0)
        (effects (font (size 1.27 1.27) (thickness 0.15)) (justify left bottom) hide)
      )
      (property "License" "Apache-2.0" (at 13.97 -27.94 0)
        (effects (font (size 1.27 1.27) (thickness 0.15)) (justify left bottom) hide)
      )
      (property "ki_keywords" "INDUCTOR, PASSIVE, SMT" (at 0 0 0)
        (effects (font (size 1.27 1.27)) hide)
      )
      (property "ki_description" "Power Inductor (SMD), 7.2 µH, 7.9 A, Shielded, 6 A, WE-PDF" (at 0 0 0)
        (effects (font (size 1.27 1.27)) hide)
      )
      (symbol "L_7u2_7.9A_WE-PDF-1064_0_1"
        (arc (start 1.524 0) (mid 1.016 0.5058) (end 0.508 0)
          (stroke (width 0) (type default))
          (fill (type none))
        )
        (arc (start 2.54 0) (mid 2.032 0.5058) (end 1.524 0)
          (stroke (width 0) (type default))
          (fill (type none))
        )
        (arc (start 3.556 0) (mid 3.048 0.5058) (end 2.54 0)
          (stroke (width 0) (type default))
          (fill (type none))
        )
        (arc (start 4.572 0) (mid 4.064 0.5058) (end 3.556 0)
          (stroke (width 0) (type default))
          (fill (type none))
        )
      )
      (symbol "L_7u2_7.9A_WE-PDF-1064_1_1"
        (pin passive line (at 0 0 0) (length 0.508)
          (name "~" (effects (font (size 1.27 1.27))))
          (number "1" (effects (font (size 1.27 1.27))))
        )
        (pin passive line (at 5.08 0 180) (length 0.508)
          (name "~" (effects (font (size 1.27 1.27))))
          (number "2" (effects (font (size 1.27 1.27))))
        )
      )
    )
	(symbol "antmicroFixedInductors:L_800n_13A_Coilcraft-XAL5030" (pin_numbers hide) (pin_names hide) (in_bom yes) (on_board yes)
      (property "Reference" "L" (at 13.97 0 0)
        (effects (font (size 1.27 1.27) (thickness 0.15)) (justify left bottom))
      )
      (property "Value" "L_800n_13A_Coilcraft-XAL5030" (at 13.97 -2.54 0)
        (effects (font (size 1.27 1.27) (thickness 0.15)) (justify left bottom) hide)
      )
      (property "Footprint" "antmicro-footprints:L_Coilcraft-XAL5030" (at 13.97 -7.62 0)
        (effects (font (size 1.27 1.27) (thickness 0.15)) (justify left bottom) hide)
      )
      (property "Datasheet" "https://eu.mouser.com/datasheet/2/597/xal50xx-270657.pdf" (at 13.97 -10.16 0)
        (effects (font (size 1.27 1.27) (thickness 0.15)) (justify left bottom) hide)
      )
      (property "Val" "800n/13A" (at 13.97 -5.08 0)
        (effects (font (size 1.27 1.27) (thickness 0.15)) (justify left bottom))
      )
      (property "Manufacturer" "Coilcraft" (at 13.97 -12.7 0)
        (effects (font (size 1.27 1.27) (thickness 0.15)) (justify left bottom) hide)
      )
      (property "MPN" "XAL5030-801MEC" (at 13.97 -15.24 0)
        (effects (font (size 1.27 1.27) (thickness 0.15)) (justify left bottom) hide)
      )
      (property "ISat" "18.5 A" (at 13.97 -16.51 0)
        (effects (font (size 1.27 1.27)) (justify left) hide)
      )
      (property "IMax" "13 A" (at 13.97 -20.32 0)
        (effects (font (size 1.27 1.27) (thickness 0.15)) (justify left bottom) hide)
      )
      (property "Size" "5.28x5.48" (at 13.97 -22.86 0)
        (effects (font (size 1.27 1.27) (thickness 0.15)) (justify left bottom) hide)
      )
      (property "Author" "Antmicro" (at 13.97 -25.4 0)
        (effects (font (size 1.27 1.27) (thickness 0.15)) (justify left bottom) hide)
      )
      (property "License" "Apache-2.0" (at 13.97 -27.94 0)
        (effects (font (size 1.27 1.27) (thickness 0.15)) (justify left bottom) hide)
      )
      (property "ki_keywords" "SMT, INDUCTOR, PASSIVE" (at 0 0 0)
        (effects (font (size 1.27 1.27)) hide)
      )
      (property "ki_description" "Power Inductor (SMD), 800 nH, 13 A, Shielded, 18.5 A, XAL5030" (at 0 0 0)
        (effects (font (size 1.27 1.27)) hide)
      )
      (symbol "L_800n_13A_Coilcraft-XAL5030_0_1"
        (arc (start 1.524 0) (mid 1.016 0.5058) (end 0.508 0)
          (stroke (width 0) (type default))
          (fill (type none))
        )
        (arc (start 2.54 0) (mid 2.032 0.5058) (end 1.524 0)
          (stroke (width 0) (type default))
          (fill (type none))
        )
        (arc (start 3.556 0) (mid 3.048 0.5058) (end 2.54 0)
          (stroke (width 0) (type default))
          (fill (type none))
        )
        (arc (start 4.572 0) (mid 4.064 0.5058) (end 3.556 0)
          (stroke (width 0) (type default))
          (fill (type none))
        )
      )
      (symbol "L_800n_13A_Coilcraft-XAL5030_1_1"
        (pin passive line (at 0 0 0) (length 0.508)
          (name "~" (effects (font (size 1.27 1.27))))
          (number "1" (effects (font (size 1.27 1.27))))
        )
        (pin passive line (at 5.08 0 180) (length 0.508)
          (name "~" (effects (font (size 1.27 1.27))))
          (number "2" (effects (font (size 1.27 1.27))))
        )
      )
    )
	(symbol "antmicroFuses:F_3A_1206" (pin_numbers hide) (pin_names (offset 0.9906) hide) (in_bom yes) (on_board yes)
      (property "Reference" "F" (at 20.32 -5.08 0)
        (effects (font (size 1.27 1.27) (thickness 0.15)) (justify left bottom))
      )
      (property "Value" "F_3A_1206" (at 20.32 -7.62 0)
        (effects (font (size 1.27 1.27) (thickness 0.15)) (justify left bottom) hide)
      )
      (property "Footprint" "antmicro-footprints:F_1206_3216Metric" (at 20.32 -10.16 0)
        (effects (font (size 1.27 1.27) (thickness 0.15)) (justify left bottom) hide)
      )
      (property "Datasheet" "https://www.littelfuse.com/~/media/electronics/datasheets/fuses/littelfuse_fuse_466_datasheet.pdf.pdf" (at 20.32 -12.7 0)
        (effects (font (size 1.27 1.27) (thickness 0.15)) (justify left bottom) hide)
      )
      (property "Manufacturer" "Littelfuse" (at 20.32 -15.24 0)
        (effects (font (size 1.27 1.27) (thickness 0.15)) (justify left bottom) hide)
      )
      (property "MPN" "0466003.NR " (at 20.32 -17.78 0)
        (effects (font (size 1.27 1.27) (thickness 0.15)) (justify left bottom))
      )
      (property "Author" "Antmicro" (at 20.32 -20.32 0)
        (effects (font (size 1.27 1.27) (thickness 0.15)) (justify left bottom) hide)
      )
      (property "License" "Apache-2.0" (at 20.32 -22.86 0)
        (effects (font (size 1.27 1.27) (thickness 0.15)) (justify left bottom) hide)
      )
      (property "ki_keywords" "FUSE, PASSIVE" (at 0 0 0)
        (effects (font (size 1.27 1.27)) hide)
      )
      (property "ki_description" "Fuse, Surface Mount, 3 A, Very Fast Acting, 32 V, 32 V, 1206 (3216 Metric), 466" (at 0 0 0)
        (effects (font (size 1.27 1.27)) hide)
      )
      (symbol "F_3A_1206_0_1"
        (polyline
          (pts
            (xy 1.27 0)
            (xy 3.81 0)
          )
          (stroke (width 0) (type default))
          (fill (type none))
        )
        (rectangle (start 1.27 0.508) (end 3.81 -0.508)
          (stroke (width 0) (type default))
          (fill (type none))
        )
      )
      (symbol "F_3A_1206_1_1"
        (pin passive line (at 0 0 0) (length 1.27)
          (name "~" (effects (font (size 1.27 1.27))))
          (number "1" (effects (font (size 1.27 1.27))))
        )
        (pin passive line (at 5.08 0 180) (length 1.27)
          (name "~" (effects (font (size 1.27 1.27))))
          (number "2" (effects (font (size 1.27 1.27))))
        )
      )
    )
	(symbol "antmicroGenericPinHeaders:PinHeader_1x6_P2.54mm_Drill1.1mm" (in_bom yes) (on_board yes)
      (property "Reference" "J" (at 20.32 -5.08 0)
        (effects (font (size 1.27 1.27) (thickness 0.15)) (justify left bottom))
      )
      (property "Value" "PinHeader_1x6_P2.54mm_Drill1.1mm" (at 20.32 -7.62 0)
        (effects (font (size 1.27 1.27) (thickness 0.15)) (justify left bottom) hide)
      )
      (property "Footprint" "antmicro-footprints:PinHeader_1x6_P2.54mm_Drill1.1mm" (at 20.32 -10.16 0)
        (effects (font (size 1.27 1.27) (thickness 0.15)) (justify left bottom) hide)
      )
      (property "Datasheet" "https://www.we-online.com/components/products/datasheet/61300611121.pdf" (at 20.32 -12.7 0)
        (effects (font (size 1.27 1.27) (thickness 0.15)) (justify left bottom) hide)
      )
      (property "MPN" "61300611121" (at 20.32 -15.24 0)
        (effects (font (size 1.27 1.27) (thickness 0.15)) (justify left bottom))
      )
      (property "Manufacturer" "Würth Elektronik" (at 20.32 -17.78 0)
        (effects (font (size 1.27 1.27) (thickness 0.15)) (justify left bottom) hide)
      )
      (property "Author" "Antmicro" (at 20.32 -20.32 0)
        (effects (font (size 1.27 1.27) (thickness 0.15)) (justify left bottom) hide)
      )
      (property "License" "Apache-2.0" (at 20.32 -22.86 0)
        (effects (font (size 1.27 1.27) (thickness 0.15)) (justify left bottom) hide)
      )
      (property "ki_keywords" "VERTICAL, THT, HEADER, CONNECTOR, MALE" (at 0 0 0)
        (effects (font (size 1.27 1.27)) hide)
      )
      (property "ki_description" "Pin Header, Vertical, Board-to-Board, 2.54 mm, 1 Rows, 6 Contacts, Through Hole Straight, WR-PHD" (at 0 0 0)
        (effects (font (size 1.27 1.27)) hide)
      )
      (symbol "PinHeader_1x6_P2.54mm_Drill1.1mm_1_1"
        (rectangle (start 4.191 -12.954) (end 3.683 -12.446)
          (stroke (width 0.254) (type default))
          (fill (type outline))
        )
        (rectangle (start 4.191 -10.414) (end 3.683 -9.906)
          (stroke (width 0.254) (type default))
          (fill (type outline))
        )
        (rectangle (start 4.191 -7.874) (end 3.683 -7.366)
          (stroke (width 0.254) (type default))
          (fill (type outline))
        )
        (rectangle (start 4.191 -5.334) (end 3.683 -4.826)
          (stroke (width 0.254) (type default))
          (fill (type outline))
        )
        (rectangle (start 4.191 -2.794) (end 3.683 -2.286)
          (stroke (width 0.254) (type default))
          (fill (type outline))
        )
        (rectangle (start 4.191 -0.254) (end 3.683 0.254)
          (stroke (width 0.254) (type default))
          (fill (type outline))
        )
        (rectangle (start 5.08 -13.97) (end 2.54 1.27)
          (stroke (width 0.254) (type default))
          (fill (type background))
        )
        (pin passive line (at 0 0 0) (length 2.54)
          (name "~" (effects (font (size 1.27 1.27))))
          (number "1" (effects (font (size 1.27 1.27))))
        )
        (pin passive line (at 0 -2.54 0) (length 2.54)
          (name "~" (effects (font (size 1.27 1.27))))
          (number "2" (effects (font (size 1.27 1.27))))
        )
        (pin passive line (at 0 -5.08 0) (length 2.54)
          (name "~" (effects (font (size 1.27 1.27))))
          (number "3" (effects (font (size 1.27 1.27))))
        )
        (pin passive line (at 0 -7.62 0) (length 2.54)
          (name "~" (effects (font (size 1.27 1.27))))
          (number "4" (effects (font (size 1.27 1.27))))
        )
        (pin passive line (at 0 -10.16 0) (length 2.54)
          (name "~" (effects (font (size 1.27 1.27))))
          (number "5" (effects (font (size 1.27 1.27))))
        )
        (pin passive line (at 0 -12.7 0) (length 2.54)
          (name "~" (effects (font (size 1.27 1.27))))
          (number "6" (effects (font (size 1.27 1.27))))
        )
      )
    )
	(symbol "antmicroGenericPinHeaders:PinHeader_2x7_P2mm_Drill1mm_Shrouded" (in_bom yes) (on_board yes)
      (property "Reference" "J" (at 25.4 -2.54 0)
        (effects (font (size 1.27 1.27) (thickness 0.15)) (justify left bottom))
      )
      (property "Value" "PinHeader_2x7_P2mm_Drill1mm_Shrouded" (at 25.4 -5.08 0)
        (effects (font (size 1.27 1.27) (thickness 0.15)) (justify left bottom) hide)
      )
      (property "Footprint" "antmicro-footprints:PinHeader_2x7_P2mm_Drill1mm_Shrouded" (at 25.4 -7.62 0)
        (effects (font (size 1.27 1.27) (thickness 0.15)) (justify left bottom) hide)
      )
      (property "Datasheet" "https://www.molex.com/pdm_docs/sd/878322620_sd.pdf" (at 25.4 -10.16 0)
        (effects (font (size 1.27 1.27) (thickness 0.15)) (justify left bottom) hide)
      )
      (property "MPN" "0878311420" (at 25.4 -12.7 0)
        (effects (font (size 1.27 1.27) (thickness 0.15)) (justify left bottom))
      )
      (property "Manufacturer" "Molex" (at 25.4 -15.24 0)
        (effects (font (size 1.27 1.27) (thickness 0.15)) (justify left bottom) hide)
      )
      (property "Author" "Antmicro" (at 25.4 -17.78 0)
        (effects (font (size 1.27 1.27) (thickness 0.15)) (justify left bottom) hide)
      )
      (property "License" "Apache-2.0" (at 25.4 -20.32 0)
        (effects (font (size 1.27 1.27) (thickness 0.15)) (justify left bottom) hide)
      )
      (property "ki_keywords" "PINSTRIP, HEADER " (at 0 0 0)
        (effects (font (size 1.27 1.27)) hide)
      )
      (property "ki_description" "Pin Header, Wire-to-Board, 2 mm, 2 Rows, 14 Contacts, Surface Mount Straight, Milli-Grid 87832" (at 0 0 0)
        (effects (font (size 1.27 1.27)) hide)
      )
      (symbol "PinHeader_2x7_P2mm_Drill1mm_Shrouded_1_1"
        (rectangle (start 2.54 1.27) (end 7.62 -16.51)
          (stroke (width 0.254) (type default))
          (fill (type background))
        )
        (rectangle (start 3.556 -14.986) (end 4.064 -15.494)
          (stroke (width 0.254) (type default))
          (fill (type background))
        )
        (rectangle (start 3.556 -12.446) (end 4.064 -12.954)
          (stroke (width 0.254) (type default))
          (fill (type background))
        )
        (rectangle (start 3.556 -9.906) (end 4.064 -10.414)
          (stroke (width 0.254) (type default))
          (fill (type background))
        )
        (rectangle (start 3.556 -7.366) (end 4.064 -7.874)
          (stroke (width 0.254) (type default))
          (fill (type background))
        )
        (rectangle (start 3.556 -4.826) (end 4.064 -5.334)
          (stroke (width 0.254) (type default))
          (fill (type background))
        )
        (rectangle (start 3.556 -2.286) (end 4.064 -2.794)
          (stroke (width 0.254) (type default))
          (fill (type background))
        )
        (rectangle (start 3.556 0.254) (end 4.064 -0.254)
          (stroke (width 0.254) (type default))
          (fill (type background))
        )
        (rectangle (start 6.096 -14.986) (end 6.604 -15.494)
          (stroke (width 0.254) (type default))
          (fill (type background))
        )
        (rectangle (start 6.096 -12.446) (end 6.604 -12.954)
          (stroke (width 0.254) (type default))
          (fill (type background))
        )
        (rectangle (start 6.096 -9.906) (end 6.604 -10.414)
          (stroke (width 0.254) (type default))
          (fill (type background))
        )
        (rectangle (start 6.096 -7.366) (end 6.604 -7.874)
          (stroke (width 0.254) (type default))
          (fill (type background))
        )
        (rectangle (start 6.096 -4.826) (end 6.604 -5.334)
          (stroke (width 0.254) (type default))
          (fill (type background))
        )
        (rectangle (start 6.096 -2.286) (end 6.604 -2.794)
          (stroke (width 0.254) (type default))
          (fill (type background))
        )
        (rectangle (start 6.096 0.254) (end 6.604 -0.254)
          (stroke (width 0.254) (type default))
          (fill (type background))
        )
        (pin passive line (at 0 0 0) (length 2.54)
          (name "~" (effects (font (size 1.27 1.27))))
          (number "1" (effects (font (size 1.27 1.27))))
        )
        (pin passive line (at 10.16 -10.16 180) (length 2.54)
          (name "~" (effects (font (size 1.27 1.27))))
          (number "10" (effects (font (size 1.27 1.27))))
        )
        (pin passive line (at 0 -12.7 0) (length 2.54)
          (name "~" (effects (font (size 1.27 1.27))))
          (number "11" (effects (font (size 1.27 1.27))))
        )
        (pin passive line (at 10.16 -12.7 180) (length 2.54)
          (name "~" (effects (font (size 1.27 1.27))))
          (number "12" (effects (font (size 1.27 1.27))))
        )
        (pin passive line (at 0 -15.24 0) (length 2.54)
          (name "~" (effects (font (size 1.27 1.27))))
          (number "13" (effects (font (size 1.27 1.27))))
        )
        (pin passive line (at 10.16 -15.24 180) (length 2.54)
          (name "~" (effects (font (size 1.27 1.27))))
          (number "14" (effects (font (size 1.27 1.27))))
        )
        (pin passive line (at 10.16 0 180) (length 2.54)
          (name "~" (effects (font (size 1.27 1.27))))
          (number "2" (effects (font (size 1.27 1.27))))
        )
        (pin passive line (at 0 -2.54 0) (length 2.54)
          (name "~" (effects (font (size 1.27 1.27))))
          (number "3" (effects (font (size 1.27 1.27))))
        )
        (pin passive line (at 10.16 -2.54 180) (length 2.54)
          (name "~" (effects (font (size 1.27 1.27))))
          (number "4" (effects (font (size 1.27 1.27))))
        )
        (pin passive line (at 0 -5.08 0) (length 2.54)
          (name "~" (effects (font (size 1.27 1.27))))
          (number "5" (effects (font (size 1.27 1.27))))
        )
        (pin passive line (at 10.16 -5.08 180) (length 2.54)
          (name "~" (effects (font (size 1.27 1.27))))
          (number "6" (effects (font (size 1.27 1.27))))
        )
        (pin passive line (at 0 -7.62 0) (length 2.54)
          (name "~" (effects (font (size 1.27 1.27))))
          (number "7" (effects (font (size 1.27 1.27))))
        )
        (pin passive line (at 10.16 -7.62 180) (length 2.54)
          (name "~" (effects (font (size 1.27 1.27))))
          (number "8" (effects (font (size 1.27 1.27))))
        )
        (pin passive line (at 0 -10.16 0) (length 2.54)
          (name "~" (effects (font (size 1.27 1.27))))
          (number "9" (effects (font (size 1.27 1.27))))
        )
      )
    )
	(symbol "antmicroGenericPinSockets:PinSocket_2x6_P2.54mm_Drill1.02mm_PMOD" (in_bom yes) (on_board yes)
      (property "Reference" "J" (at 25.4 -5.08 0)
        (effects (font (size 1.27 1.27) (thickness 0.15)) (justify left bottom))
      )
      (property "Value" "PinSocket_2x6_P2.54mm_Drill1.02mm_PMOD" (at 25.4 -7.62 0)
        (effects (font (size 1.27 1.27) (thickness 0.15)) (justify left bottom) hide)
      )
      (property "Footprint" "antmicro-footprints:PinSocket_2x6_P2.54mm_Drill1.02mm_PMOD" (at 25.4 -10.16 0)
        (effects (font (size 1.27 1.27) (thickness 0.15)) (justify left bottom) hide)
      )
      (property "Datasheet" "https://cdn.harwin.com/pdfs/M20-783.pdf" (at 25.4 -12.7 0)
        (effects (font (size 1.27 1.27) (thickness 0.15)) (justify left bottom) hide)
      )
      (property "MPN" "M20-7830642" (at 25.4 -15.24 0)
        (effects (font (size 1.27 1.27) (thickness 0.15)) (justify left bottom))
      )
      (property "Manufacturer" "Harwin" (at 25.4 -17.78 0)
        (effects (font (size 1.27 1.27) (thickness 0.15)) (justify left bottom) hide)
      )
      (property "Author" "Antmicro" (at 25.4 -20.32 0)
        (effects (font (size 1.27 1.27) (thickness 0.15)) (justify left bottom) hide)
      )
      (property "License" "Apache-2.0" (at 25.4 -22.86 0)
        (effects (font (size 1.27 1.27) (thickness 0.15)) (justify left bottom) hide)
      )
      (property "ki_keywords" "CONNECTOR, HEADER" (at 0 0 0)
        (effects (font (size 1.27 1.27)) hide)
      )
      (property "ki_description" "PCB Receptacle, Board-to-Board, 2.54 mm, 2 Rows, 12 Contacts, Through Hole Mount, M20" (at 0 0 0)
        (effects (font (size 1.27 1.27)) hide)
      )
      (symbol "PinSocket_2x6_P2.54mm_Drill1.02mm_PMOD_0_1"
        (rectangle (start 3.556 -12.446) (end 4.064 -12.954)
          (stroke (width 0) (type default))
          (fill (type outline))
        )
        (rectangle (start 3.556 -9.906) (end 4.064 -10.414)
          (stroke (width 0) (type default))
          (fill (type outline))
        )
        (rectangle (start 3.556 -7.366) (end 4.064 -7.874)
          (stroke (width 0) (type default))
          (fill (type outline))
        )
        (rectangle (start 3.556 -4.826) (end 4.064 -5.334)
          (stroke (width 0) (type default))
          (fill (type outline))
        )
        (rectangle (start 3.556 -2.286) (end 4.064 -2.794)
          (stroke (width 0) (type default))
          (fill (type outline))
        )
        (rectangle (start 3.556 0.254) (end 4.064 -0.254)
          (stroke (width 0) (type default))
          (fill (type outline))
        )
        (rectangle (start 5.842 -12.446) (end 6.35 -12.954)
          (stroke (width 0) (type default))
          (fill (type outline))
        )
        (rectangle (start 5.842 -9.906) (end 6.35 -10.414)
          (stroke (width 0) (type default))
          (fill (type outline))
        )
        (rectangle (start 5.842 -7.366) (end 6.35 -7.874)
          (stroke (width 0) (type default))
          (fill (type outline))
        )
        (rectangle (start 5.842 -4.826) (end 6.35 -5.334)
          (stroke (width 0) (type default))
          (fill (type outline))
        )
        (rectangle (start 5.842 -2.286) (end 6.35 -2.794)
          (stroke (width 0) (type default))
          (fill (type outline))
        )
        (rectangle (start 5.842 0.254) (end 6.35 -0.254)
          (stroke (width 0) (type default))
          (fill (type outline))
        )
      )
      (symbol "PinSocket_2x6_P2.54mm_Drill1.02mm_PMOD_1_1"
        (rectangle (start 2.54 1.27) (end 7.62 -13.97)
          (stroke (width 0.254) (type default))
          (fill (type background))
        )
        (pin passive line (at 0 0 0) (length 2.54)
          (name "~" (effects (font (size 1.27 1.27))))
          (number "1" (effects (font (size 1.27 1.27))))
        )
        (pin passive line (at 10.16 -7.62 180) (length 2.54)
          (name "~" (effects (font (size 1.27 1.27))))
          (number "10" (effects (font (size 1.27 1.27))))
        )
        (pin passive line (at 10.16 -10.16 180) (length 2.54)
          (name "~" (effects (font (size 1.27 1.27))))
          (number "11" (effects (font (size 1.27 1.27))))
        )
        (pin passive line (at 10.16 -12.7 180) (length 2.54)
          (name "~" (effects (font (size 1.27 1.27))))
          (number "12" (effects (font (size 1.27 1.27))))
        )
        (pin passive line (at 0 -2.54 0) (length 2.54)
          (name "~" (effects (font (size 1.27 1.27))))
          (number "2" (effects (font (size 1.27 1.27))))
        )
        (pin passive line (at 0 -5.08 0) (length 2.54)
          (name "~" (effects (font (size 1.27 1.27))))
          (number "3" (effects (font (size 1.27 1.27))))
        )
        (pin passive line (at 0 -7.62 0) (length 2.54)
          (name "~" (effects (font (size 1.27 1.27))))
          (number "4" (effects (font (size 1.27 1.27))))
        )
        (pin passive line (at 0 -10.16 0) (length 2.54)
          (name "~" (effects (font (size 1.27 1.27))))
          (number "5" (effects (font (size 1.27 1.27))))
        )
        (pin passive line (at 0 -12.7 0) (length 2.54)
          (name "~" (effects (font (size 1.27 1.27))))
          (number "6" (effects (font (size 1.27 1.27))))
        )
        (pin passive line (at 10.16 0 180) (length 2.54)
          (name "~" (effects (font (size 1.27 1.27))))
          (number "7" (effects (font (size 1.27 1.27))))
        )
        (pin passive line (at 10.16 -2.54 180) (length 2.54)
          (name "~" (effects (font (size 1.27 1.27))))
          (number "8" (effects (font (size 1.27 1.27))))
        )
        (pin passive line (at 10.16 -5.08 180) (length 2.54)
          (name "~" (effects (font (size 1.27 1.27))))
          (number "9" (effects (font (size 1.27 1.27))))
        )
      )
    )
	(symbol "antmicroInterfaceControllers:FT4232H_VQFN" (in_bom yes) (on_board yes)
      (property "Reference" "U" (at 55.88 -2.54 0)
        (effects (font (size 1.27 1.27) (thickness 0.15)) (justify left bottom))
      )
      (property "Value" "FT4232H_VQFN" (at 55.88 -15.24 0)
        (effects (font (size 1.27 1.27) (thickness 0.15)) (justify left bottom) hide)
      )
      (property "Footprint" "antmicro-footprints:QFN-56-1EP_8x8mm_P0.5mm" (at 55.88 -7.62 0)
        (effects (font (size 1.27 1.27) (thickness 0.15)) (justify left bottom) hide)
      )
      (property "Datasheet" "https://www.ftdichip.com/Support/Documents/DataSheets/ICs/DS_FT4232H.pdf" (at 55.88 -10.16 0)
        (effects (font (size 1.27 1.27) (thickness 0.15)) (justify left bottom) hide)
      )
      (property "Manufacturer" "FTDI Chip" (at 55.88 -12.7 0)
        (effects (font (size 1.27 1.27) (thickness 0.15)) (justify left bottom) hide)
      )
      (property "MPN" "FT4232H-56Q-REEL" (at 55.88 -5.08 0)
        (effects (font (size 1.27 1.27) (thickness 0.15)) (justify left bottom))
      )
      (property "Author" "Antmicro" (at 55.88 -17.78 0)
        (effects (font (size 1.27 1.27) (thickness 0.15)) (justify left bottom) hide)
      )
      (property "License" "Apache-2.0" (at 55.88 -20.32 0)
        (effects (font (size 1.27 1.27) (thickness 0.15)) (justify left bottom) hide)
      )
      (property "ki_keywords" "SMT, INTERFACE, IC, CONTROLLER, USB, UART, I2C, SPI, JTAG" (at 0 0 0)
        (effects (font (size 1.27 1.27)) hide)
      )
      (property "ki_description" "Interface Bridges, USB to UART, MPSSE, 1.62 V, 1.98 V, VQFN, 56 Pins, -40 °C" (at 0 0 0)
        (effects (font (size 1.27 1.27)) hide)
      )
      (symbol "FT4232H_VQFN_1_1"
        (rectangle (start 2.54 2.54) (end 38.1 -93.98)
          (stroke (width 0.254) (type default))
          (fill (type background))
        )
        (pin bidirectional line (at 0 -44.45 0) (length 2.54)
          (name "EECS" (effects (font (size 1.27 1.27))))
          (number "1" (effects (font (size 1.27 1.27))))
        )
        (pin input line (at 0 -88.9 0) (length 2.54)
          (name "TEST" (effects (font (size 1.27 1.27))))
          (number "10" (effects (font (size 1.27 1.27))))
        )
        (pin input line (at 0 -36.83 0) (length 2.54)
          (name "~{RESET}" (effects (font (size 1.27 1.27))))
          (number "11" (effects (font (size 1.27 1.27))))
        )
        (pin bidirectional line (at 40.64 0 180) (length 2.54)
          (name "ADBUS0" (effects (font (size 1.27 1.27))))
          (number "12" (effects (font (size 1.27 1.27))))
        )
        (pin bidirectional line (at 40.64 -2.54 180) (length 2.54)
          (name "ADBUS1" (effects (font (size 1.27 1.27))))
          (number "13" (effects (font (size 1.27 1.27))))
        )
        (pin bidirectional line (at 40.64 -5.08 180) (length 2.54)
          (name "ADBUS2" (effects (font (size 1.27 1.27))))
          (number "14" (effects (font (size 1.27 1.27))))
        )
        (pin bidirectional line (at 40.64 -7.62 180) (length 2.54)
          (name "ADBUS3" (effects (font (size 1.27 1.27))))
          (number "15" (effects (font (size 1.27 1.27))))
        )
        (pin power_in line (at 0 -2.54 0) (length 2.54)
          (name "V_{CCIO}" (effects (font (size 1.27 1.27))))
          (number "16" (effects (font (size 1.27 1.27))))
        )
        (pin bidirectional line (at 40.64 -10.16 180) (length 2.54)
          (name "ADBUS4" (effects (font (size 1.27 1.27))))
          (number "17" (effects (font (size 1.27 1.27))))
        )
        (pin bidirectional line (at 40.64 -12.7 180) (length 2.54)
          (name "ADBUS5" (effects (font (size 1.27 1.27))))
          (number "18" (effects (font (size 1.27 1.27))))
        )
        (pin bidirectional line (at 40.64 -15.24 180) (length 2.54)
          (name "ADBUS6" (effects (font (size 1.27 1.27))))
          (number "19" (effects (font (size 1.27 1.27))))
        )
        (pin power_in line (at 0 -15.24 0) (length 2.54)
          (name "V_{CORE}" (effects (font (size 1.27 1.27))))
          (number "2" (effects (font (size 1.27 1.27))))
        )
        (pin bidirectional line (at 40.64 -17.78 180) (length 2.54)
          (name "ADBUS7" (effects (font (size 1.27 1.27))))
          (number "20" (effects (font (size 1.27 1.27))))
        )
        (pin power_in line (at 0 -91.44 0) (length 2.54)
          (name "GND" (effects (font (size 1.27 1.27))))
          (number "21" (effects (font (size 1.27 1.27))))
        )
        (pin bidirectional line (at 40.64 -21.59 180) (length 2.54)
          (name "BDBUS0" (effects (font (size 1.27 1.27))))
          (number "22" (effects (font (size 1.27 1.27))))
        )
        (pin bidirectional line (at 40.64 -24.13 180) (length 2.54)
          (name "BDBUS1" (effects (font (size 1.27 1.27))))
          (number "23" (effects (font (size 1.27 1.27))))
        )
        (pin bidirectional line (at 40.64 -26.67 180) (length 2.54)
          (name "BDBUS2" (effects (font (size 1.27 1.27))))
          (number "24" (effects (font (size 1.27 1.27))))
        )
        (pin bidirectional line (at 40.64 -29.21 180) (length 2.54)
          (name "BDBUS3" (effects (font (size 1.27 1.27))))
          (number "25" (effects (font (size 1.27 1.27))))
        )
        (pin bidirectional line (at 40.64 -31.75 180) (length 2.54)
          (name "BDBUS4" (effects (font (size 1.27 1.27))))
          (number "26" (effects (font (size 1.27 1.27))))
        )
        (pin bidirectional line (at 40.64 -34.29 180) (length 2.54)
          (name "BDBUS5" (effects (font (size 1.27 1.27))))
          (number "27" (effects (font (size 1.27 1.27))))
        )
        (pin bidirectional line (at 40.64 -36.83 180) (length 2.54)
          (name "BDBUS6" (effects (font (size 1.27 1.27))))
          (number "28" (effects (font (size 1.27 1.27))))
        )
        (pin bidirectional line (at 40.64 -39.37 180) (length 2.54)
          (name "BDBUS7" (effects (font (size 1.27 1.27))))
          (number "29" (effects (font (size 1.27 1.27))))
        )
        (pin input line (at 0 -54.61 0) (length 2.54)
          (name "OSCI" (effects (font (size 1.27 1.27))))
          (number "3" (effects (font (size 1.27 1.27))))
        )
        (pin output line (at 40.64 -90.17 180) (length 2.54)
          (name "~{SUSPEND}" (effects (font (size 1.27 1.27))))
          (number "30" (effects (font (size 1.27 1.27))))
        )
        (pin passive line (at 0 -15.24 0) (length 2.54) hide
          (name "V_{CORE}" (effects (font (size 1.27 1.27))))
          (number "31" (effects (font (size 1.27 1.27))))
        )
        (pin bidirectional line (at 40.64 -43.18 180) (length 2.54)
          (name "CDBUS0" (effects (font (size 1.27 1.27))))
          (number "32" (effects (font (size 1.27 1.27))))
        )
        (pin bidirectional line (at 40.64 -45.72 180) (length 2.54)
          (name "CDBUS1" (effects (font (size 1.27 1.27))))
          (number "33" (effects (font (size 1.27 1.27))))
        )
        (pin bidirectional line (at 40.64 -48.26 180) (length 2.54)
          (name "CDBUS2" (effects (font (size 1.27 1.27))))
          (number "34" (effects (font (size 1.27 1.27))))
        )
        (pin bidirectional line (at 40.64 -50.8 180) (length 2.54)
          (name "CDBUS3" (effects (font (size 1.27 1.27))))
          (number "35" (effects (font (size 1.27 1.27))))
        )
        (pin passive line (at 0 -2.54 0) (length 2.54) hide
          (name "V_{CCIO}" (effects (font (size 1.27 1.27))))
          (number "36" (effects (font (size 1.27 1.27))))
        )
        (pin bidirectional line (at 40.64 -53.34 180) (length 2.54)
          (name "CDBUS4" (effects (font (size 1.27 1.27))))
          (number "37" (effects (font (size 1.27 1.27))))
        )
        (pin bidirectional line (at 40.64 -55.88 180) (length 2.54)
          (name "CDBUS5" (effects (font (size 1.27 1.27))))
          (number "38" (effects (font (size 1.27 1.27))))
        )
        (pin bidirectional line (at 40.64 -58.42 180) (length 2.54)
          (name "CDBUS6" (effects (font (size 1.27 1.27))))
          (number "39" (effects (font (size 1.27 1.27))))
        )
        (pin output line (at 0 -59.69 0) (length 2.54)
          (name "OSCO" (effects (font (size 1.27 1.27))))
          (number "4" (effects (font (size 1.27 1.27))))
        )
        (pin bidirectional line (at 40.64 -60.96 180) (length 2.54)
          (name "CDBUS7" (effects (font (size 1.27 1.27))))
          (number "40" (effects (font (size 1.27 1.27))))
        )
        (pin passive line (at 0 -91.44 0) (length 2.54) hide
          (name "GND" (effects (font (size 1.27 1.27))))
          (number "41" (effects (font (size 1.27 1.27))))
        )
        (pin bidirectional line (at 40.64 -64.77 180) (length 2.54)
          (name "DDBUS0" (effects (font (size 1.27 1.27))))
          (number "42" (effects (font (size 1.27 1.27))))
        )
        (pin power_out line (at 0 -6.35 0) (length 2.54)
          (name "V_{REGOUT}" (effects (font (size 1.27 1.27))))
          (number "43" (effects (font (size 1.27 1.27))))
        )
        (pin power_in line (at 0 0 0) (length 2.54)
          (name "V_{REGIN}" (effects (font (size 1.27 1.27))))
          (number "44" (effects (font (size 1.27 1.27))))
        )
        (pin passive line (at 0 -91.44 0) (length 2.54) hide
          (name "GND" (effects (font (size 1.27 1.27))))
          (number "45" (effects (font (size 1.27 1.27))))
        )
        (pin bidirectional line (at 40.64 -67.31 180) (length 2.54)
          (name "DDBUS1" (effects (font (size 1.27 1.27))))
          (number "46" (effects (font (size 1.27 1.27))))
        )
        (pin bidirectional line (at 40.64 -69.85 180) (length 2.54)
          (name "DDBUS2" (effects (font (size 1.27 1.27))))
          (number "47" (effects (font (size 1.27 1.27))))
        )
        (pin bidirectional line (at 40.64 -72.39 180) (length 2.54)
          (name "DDBUS3" (effects (font (size 1.27 1.27))))
          (number "48" (effects (font (size 1.27 1.27))))
        )
        (pin bidirectional line (at 40.64 -74.93 180) (length 2.54)
          (name "DDBUS4" (effects (font (size 1.27 1.27))))
          (number "49" (effects (font (size 1.27 1.27))))
        )
        (pin power_in line (at 0 -10.16 0) (length 2.54)
          (name "V_{PHY}" (effects (font (size 1.27 1.27))))
          (number "5" (effects (font (size 1.27 1.27))))
        )
        (pin passive line (at 0 -2.54 0) (length 2.54) hide
          (name "V_{CCIO}" (effects (font (size 1.27 1.27))))
          (number "50" (effects (font (size 1.27 1.27))))
        )
        (pin bidirectional line (at 40.64 -77.47 180) (length 2.54)
          (name "DDBUS5" (effects (font (size 1.27 1.27))))
          (number "51" (effects (font (size 1.27 1.27))))
        )
        (pin bidirectional line (at 40.64 -80.01 180) (length 2.54)
          (name "DDBUS6" (effects (font (size 1.27 1.27))))
          (number "52" (effects (font (size 1.27 1.27))))
        )
        (pin bidirectional line (at 40.64 -82.55 180) (length 2.54)
          (name "DDBUS7" (effects (font (size 1.27 1.27))))
          (number "53" (effects (font (size 1.27 1.27))))
        )
        (pin output line (at 40.64 -87.63 180) (length 2.54)
          (name "~{PWR_{EN}}" (effects (font (size 1.27 1.27))))
          (number "54" (effects (font (size 1.27 1.27))))
        )
        (pin bidirectional line (at 0 -49.53 0) (length 2.54)
          (name "EEDATA" (effects (font (size 1.27 1.27))))
          (number "55" (effects (font (size 1.27 1.27))))
        )
        (pin output line (at 0 -46.99 0) (length 2.54)
          (name "EECLK" (effects (font (size 1.27 1.27))))
          (number "56" (effects (font (size 1.27 1.27))))
        )
        (pin passive line (at 0 -91.44 0) (length 2.54) hide
          (name "GND" (effects (font (size 1.27 1.27))))
          (number "57" (effects (font (size 1.27 1.27))))
        )
        (pin input line (at 0 -77.47 0) (length 2.54)
          (name "REF" (effects (font (size 1.27 1.27))))
          (number "6" (effects (font (size 1.27 1.27))))
        )
        (pin bidirectional line (at 0 -25.4 0) (length 2.54)
          (name "D-" (effects (font (size 1.27 1.27))))
          (number "7" (effects (font (size 1.27 1.27))))
        )
        (pin bidirectional line (at 0 -22.86 0) (length 2.54)
          (name "D+" (effects (font (size 1.27 1.27))))
          (number "8" (effects (font (size 1.27 1.27))))
        )
        (pin power_in line (at 0 -12.7 0) (length 2.54)
          (name "V_{PLL}" (effects (font (size 1.27 1.27))))
          (number "9" (effects (font (size 1.27 1.27))))
        )
      )
    )
	(symbol "antmicroInterfaceControllers:KSZ9031RNXCA" (in_bom yes) (on_board yes)
      (property "Reference" "U" (at 76.2 -5.08 0)
        (effects (font (size 1.27 1.27) (thickness 0.15)) (justify left bottom))
      )
      (property "Value" "KSZ9031RNXCA" (at 76.2 -7.62 0)
        (effects (font (size 1.27 1.27) (thickness 0.15)) (justify left bottom) hide)
      )
      (property "Footprint" "antmicro-footprints:QFN-48-1EP_7x7x0.9mm_P0.5mm_EP3.5x3.5mm" (at 76.2 -10.16 0)
        (effects (font (size 1.27 1.27) (thickness 0.15)) (justify left bottom) hide)
      )
      (property "Datasheet" "http://ww1.microchip.com/downloads/en/DeviceDoc/00002117F.pdf" (at 76.2 -12.7 0)
        (effects (font (size 1.27 1.27) (thickness 0.15)) (justify left bottom) hide)
      )
      (property "Manufacturer" "Microchip Technology" (at 76.2 -15.24 0)
        (effects (font (size 1.27 1.27) (thickness 0.15)) (justify left bottom) hide)
      )
      (property "MPN" "KSZ9031RNXCA" (at 76.2 -17.78 0)
        (effects (font (size 1.27 1.27) (thickness 0.15)) (justify left bottom))
      )
      (property "Author" "Antmicro" (at 76.2 -20.32 0)
        (effects (font (size 1.27 1.27) (thickness 0.15)) (justify left bottom) hide)
      )
      (property "License" "Apache-2.0" (at 76.2 -22.86 0)
        (effects (font (size 1.27 1.27) (thickness 0.15)) (justify left bottom) hide)
      )
      (property "ki_keywords" "SMT, TRANSCEIVER, IC, ETHERNET, PHY" (at 0 0 0)
        (effects (font (size 1.27 1.27)) hide)
      )
      (property "ki_description" "Ethernet Controller, 1000 Mbps, IEEE 802.3, 1.14 V, 3.465 V, QFN, 48 Pins" (at 0 0 0)
        (effects (font (size 1.27 1.27)) hide)
      )
      (symbol "KSZ9031RNXCA_1_1"
        (rectangle (start 2.54 2.54) (end 41.91 -62.23)
          (stroke (width 0.254) (type default))
          (fill (type background))
        )
        (text "10/100/1000" (at 21.59 -1.27 0)
          (effects (font (size 1.27 1.27) (thickness 0.15)) (justify bottom))
        )
        (text "Ethernet PHY" (at 21.59 -3.81 0)
          (effects (font (size 1.27 1.27) (thickness 0.15)) (justify bottom))
        )
        (pin power_in line (at 0 -3.81 0) (length 2.54)
          (name "AVDDH" (effects (font (size 1.27 1.27))))
          (number "1" (effects (font (size 1.27 1.27))))
        )
        (pin bidirectional line (at 44.45 -33.02 180) (length 2.54)
          (name "TXRXP_D" (effects (font (size 1.27 1.27))))
          (number "10" (effects (font (size 1.27 1.27))))
        )
        (pin bidirectional line (at 44.45 -35.56 180) (length 2.54)
          (name "TXRXM_D" (effects (font (size 1.27 1.27))))
          (number "11" (effects (font (size 1.27 1.27))))
        )
        (pin passive line (at 0 -3.81 0) (length 2.54) hide
          (name "AVDDH" (effects (font (size 1.27 1.27))))
          (number "12" (effects (font (size 1.27 1.27))))
        )
        (pin no_connect line (at 25.4 -62.23 90) (length 2.54) hide
          (name "NC" (effects (font (size 1.27 1.27))))
          (number "13" (effects (font (size 1.27 1.27))))
        )
        (pin power_in line (at 44.45 0 180) (length 2.54)
          (name "DVDDL" (effects (font (size 1.27 1.27))))
          (number "14" (effects (font (size 1.27 1.27))))
        )
        (pin bidirectional line (at 44.45 -44.45 180) (length 2.54)
          (name "LED2/PHYAD1" (effects (font (size 1.27 1.27))))
          (number "15" (effects (font (size 1.27 1.27))))
        )
        (pin power_in line (at 0 0 0) (length 2.54)
          (name "DVDDH" (effects (font (size 1.27 1.27))))
          (number "16" (effects (font (size 1.27 1.27))))
        )
        (pin bidirectional line (at 44.45 -41.91 180) (length 2.54)
          (name "LED1/PHAD0/PME_N1" (effects (font (size 1.27 1.27))))
          (number "17" (effects (font (size 1.27 1.27))))
        )
        (pin passive line (at 44.45 0 180) (length 2.54) hide
          (name "DVDDL" (effects (font (size 1.27 1.27))))
          (number "18" (effects (font (size 1.27 1.27))))
        )
        (pin input line (at 0 -22.86 0) (length 2.54)
          (name "TXD0" (effects (font (size 1.27 1.27))))
          (number "19" (effects (font (size 1.27 1.27))))
        )
        (pin bidirectional line (at 44.45 -13.97 180) (length 2.54)
          (name "TXRXP_A" (effects (font (size 1.27 1.27))))
          (number "2" (effects (font (size 1.27 1.27))))
        )
        (pin input line (at 0 -25.4 0) (length 2.54)
          (name "TXD1" (effects (font (size 1.27 1.27))))
          (number "20" (effects (font (size 1.27 1.27))))
        )
        (pin input line (at 0 -27.94 0) (length 2.54)
          (name "TXD2" (effects (font (size 1.27 1.27))))
          (number "21" (effects (font (size 1.27 1.27))))
        )
        (pin input line (at 0 -30.48 0) (length 2.54)
          (name "TXD3" (effects (font (size 1.27 1.27))))
          (number "22" (effects (font (size 1.27 1.27))))
        )
        (pin passive line (at 44.45 0 180) (length 2.54) hide
          (name "DVDDL" (effects (font (size 1.27 1.27))))
          (number "23" (effects (font (size 1.27 1.27))))
        )
        (pin input clock (at 0 -33.02 0) (length 2.54)
          (name "GTX_CLK" (effects (font (size 1.27 1.27))))
          (number "24" (effects (font (size 1.27 1.27))))
        )
        (pin input line (at 0 -20.32 0) (length 2.54)
          (name "TX_EN" (effects (font (size 1.27 1.27))))
          (number "25" (effects (font (size 1.27 1.27))))
        )
        (pin passive line (at 44.45 0 180) (length 2.54) hide
          (name "DVDDL" (effects (font (size 1.27 1.27))))
          (number "26" (effects (font (size 1.27 1.27))))
        )
        (pin input line (at 0 -46.99 0) (length 2.54)
          (name "RXD3/MODE3" (effects (font (size 1.27 1.27))))
          (number "27" (effects (font (size 1.27 1.27))))
        )
        (pin input line (at 0 -44.45 0) (length 2.54)
          (name "RXD2/MODE2" (effects (font (size 1.27 1.27))))
          (number "28" (effects (font (size 1.27 1.27))))
        )
        (pin power_in line (at 44.45 -59.69 180) (length 2.54)
          (name "VSS" (effects (font (size 1.27 1.27))))
          (number "29" (effects (font (size 1.27 1.27))))
        )
        (pin bidirectional line (at 44.45 -16.51 180) (length 2.54)
          (name "TXRXM_A" (effects (font (size 1.27 1.27))))
          (number "3" (effects (font (size 1.27 1.27))))
        )
        (pin passive line (at 44.45 0 180) (length 2.54) hide
          (name "DVDDL" (effects (font (size 1.27 1.27))))
          (number "30" (effects (font (size 1.27 1.27))))
        )
        (pin input line (at 0 -41.91 0) (length 2.54)
          (name "RXD1/MODE1" (effects (font (size 1.27 1.27))))
          (number "31" (effects (font (size 1.27 1.27))))
        )
        (pin input line (at 0 -39.37 0) (length 2.54)
          (name "RXD0/MODE0" (effects (font (size 1.27 1.27))))
          (number "32" (effects (font (size 1.27 1.27))))
        )
        (pin input line (at 0 -36.83 0) (length 2.54)
          (name "RX_DV/CLK125_EN" (effects (font (size 1.27 1.27))))
          (number "33" (effects (font (size 1.27 1.27))))
        )
        (pin passive line (at 0 0 0) (length 2.54) hide
          (name "DVDDH" (effects (font (size 1.27 1.27))))
          (number "34" (effects (font (size 1.27 1.27))))
        )
        (pin input clock (at 0 -49.53 0) (length 2.54)
          (name "RX_CLK/PHYAD2" (effects (font (size 1.27 1.27))))
          (number "35" (effects (font (size 1.27 1.27))))
        )
        (pin input line (at 0 -13.97 0) (length 2.54)
          (name "MDC" (effects (font (size 1.27 1.27))))
          (number "36" (effects (font (size 1.27 1.27))))
        )
        (pin input line (at 0 -16.51 0) (length 2.54)
          (name "MDIO" (effects (font (size 1.27 1.27))))
          (number "37" (effects (font (size 1.27 1.27))))
        )
        (pin input line (at 0 -10.16 0) (length 2.54)
          (name "~{INT/PME}" (effects (font (size 1.27 1.27))))
          (number "38" (effects (font (size 1.27 1.27))))
        )
        (pin passive line (at 44.45 0 180) (length 2.54) hide
          (name "DVDDL" (effects (font (size 1.27 1.27))))
          (number "39" (effects (font (size 1.27 1.27))))
        )
        (pin power_in line (at 44.45 -3.81 180) (length 2.54)
          (name "AVDDL" (effects (font (size 1.27 1.27))))
          (number "4" (effects (font (size 1.27 1.27))))
        )
        (pin passive line (at 0 0 0) (length 2.54) hide
          (name "DVDDH" (effects (font (size 1.27 1.27))))
          (number "40" (effects (font (size 1.27 1.27))))
        )
        (pin input clock (at 0 -53.34 0) (length 2.54)
          (name "CLK125_NDO/LED_MODE" (effects (font (size 1.27 1.27))))
          (number "41" (effects (font (size 1.27 1.27))))
        )
        (pin input line (at 0 -7.62 0) (length 2.54)
          (name "~{RESET}" (effects (font (size 1.27 1.27))))
          (number "42" (effects (font (size 1.27 1.27))))
        )
        (pin input line (at 44.45 -8.89 180) (length 2.54)
          (name "LDO_O" (effects (font (size 1.27 1.27))))
          (number "43" (effects (font (size 1.27 1.27))))
        )
        (pin power_in line (at 44.45 -6.35 180) (length 2.54)
          (name "AVDDL_PLL" (effects (font (size 1.27 1.27))))
          (number "44" (effects (font (size 1.27 1.27))))
        )
        (pin input line (at 0 -59.69 0) (length 2.54)
          (name "XO" (effects (font (size 1.27 1.27))))
          (number "45" (effects (font (size 1.27 1.27))))
        )
        (pin input line (at 0 -57.15 0) (length 2.54)
          (name "XI" (effects (font (size 1.27 1.27))))
          (number "46" (effects (font (size 1.27 1.27))))
        )
        (pin no_connect line (at 28.575 -62.23 90) (length 2.54) hide
          (name "NC" (effects (font (size 1.27 1.27))))
          (number "47" (effects (font (size 1.27 1.27))))
        )
        (pin output line (at 44.45 -49.53 180) (length 2.54)
          (name "ISET" (effects (font (size 1.27 1.27))))
          (number "48" (effects (font (size 1.27 1.27))))
        )
        (pin power_in line (at 44.45 -57.15 180) (length 2.54)
          (name "PAD_GND" (effects (font (size 1.27 1.27))))
          (number "49" (effects (font (size 1.27 1.27))))
        )
        (pin bidirectional line (at 44.45 -20.32 180) (length 2.54)
          (name "TXRXP_B" (effects (font (size 1.27 1.27))))
          (number "5" (effects (font (size 1.27 1.27))))
        )
        (pin bidirectional line (at 44.45 -22.86 180) (length 2.54)
          (name "TXRXM_B" (effects (font (size 1.27 1.27))))
          (number "6" (effects (font (size 1.27 1.27))))
        )
        (pin bidirectional line (at 44.45 -26.67 180) (length 2.54)
          (name "TXRXP_C" (effects (font (size 1.27 1.27))))
          (number "7" (effects (font (size 1.27 1.27))))
        )
        (pin bidirectional line (at 44.45 -29.21 180) (length 2.54)
          (name "TXRXM_C" (effects (font (size 1.27 1.27))))
          (number "8" (effects (font (size 1.27 1.27))))
        )
        (pin passive line (at 44.45 -3.81 180) (length 2.54) hide
          (name "AVDDL" (effects (font (size 1.27 1.27))))
          (number "9" (effects (font (size 1.27 1.27))))
        )
      )
    )
	(symbol "antmicroInterfaceControllers:USB3300-EZK-TR" (pin_names (offset 1.016)) (in_bom yes) (on_board yes)
      (property "Reference" "U" (at 38.1 -2.54 0)
        (effects (font (size 1.27 1.27) (thickness 0.15)) (justify left bottom))
      )
      (property "Value" "USB3300-EZK-TR" (at 38.1 -5.08 0)
        (effects (font (size 1.27 1.27) (thickness 0.15)) (justify left bottom) hide)
      )
      (property "Footprint" "antmicro-footprints:QFN-32-1EP_5x5mm" (at 38.1 -7.62 0)
        (effects (font (size 1.27 1.27) (thickness 0.15)) (justify left bottom) hide)
      )
      (property "Datasheet" "https://ww1.microchip.com/downloads/en/DeviceDoc/00001783C.pdf" (at 38.1 -10.16 0)
        (effects (font (size 1.27 1.27) (thickness 0.15)) (justify left bottom) hide)
      )
      (property "Manufacturer" "Microchip Technology" (at 38.1 -12.7 0)
        (effects (font (size 1.27 1.27) (thickness 0.15)) (justify left bottom) hide)
      )
      (property "MPN" "USB3300-EZK-TR" (at 38.1 -15.24 0)
        (effects (font (size 1.27 1.27) (thickness 0.15)) (justify left bottom))
      )
      (property "Author" "Antmicro" (at 38.1 -17.78 0)
        (effects (font (size 1.27 1.27) (thickness 0.15)) (justify left bottom) hide)
      )
      (property "License" "Apache-2.0" (at 38.1 -20.32 0)
        (effects (font (size 1.27 1.27) (thickness 0.15)) (justify left bottom) hide)
      )
      (property "ki_keywords" "SMT, INTERFACE, CONTROLLER, IC, USB" (at 0 0 0)
        (effects (font (size 1.27 1.27)) hide)
      )
      (property "ki_description" "USB Interface, USB Host Controller, USB 2.0 OTG, 3 V, 3.6 V, VQFN, 32 Pins" (at 0 0 0)
        (effects (font (size 1.27 1.27)) hide)
      )
      (symbol "USB3300-EZK-TR_0_0"
        (rectangle (start 2.54 2.54) (end 21.59 -45.72)
          (stroke (width 0) (type default))
          (fill (type background))
        )
        (pin power_in line (at 0 -43.18 0) (length 2.54)
          (name "GND" (effects (font (size 1.27 1.27))))
          (number "1" (effects (font (size 1.27 1.27))))
        )
        (pin input line (at 0 -22.86 0) (length 2.54)
          (name "EXTVBUS" (effects (font (size 1.27 1.27))))
          (number "10" (effects (font (size 1.27 1.27))))
        )
        (pin output line (at 24.13 -30.48 180) (length 2.54)
          (name "NXT" (effects (font (size 1.27 1.27))))
          (number "11" (effects (font (size 1.27 1.27))))
        )
        (pin output line (at 24.13 -33.02 180) (length 2.54)
          (name "DIR" (effects (font (size 1.27 1.27))))
          (number "12" (effects (font (size 1.27 1.27))))
        )
        (pin input line (at 24.13 -35.56 180) (length 2.54)
          (name "STP" (effects (font (size 1.27 1.27))))
          (number "13" (effects (font (size 1.27 1.27))))
        )
        (pin output clock (at 24.13 -38.1 180) (length 2.54)
          (name "CLKOUT" (effects (font (size 1.27 1.27))))
          (number "14" (effects (font (size 1.27 1.27))))
        )
        (pin power_in line (at 24.13 0 180) (length 2.54)
          (name "VDD1.8" (effects (font (size 1.27 1.27))))
          (number "15" (effects (font (size 1.27 1.27))))
        )
        (pin passive line (at 0 0 0) (length 2.54) hide
          (name "VDD3.3" (effects (font (size 1.27 1.27))))
          (number "16" (effects (font (size 1.27 1.27))))
        )
        (pin bidirectional line (at 24.13 -25.4 180) (length 2.54)
          (name "DATA[7]" (effects (font (size 1.27 1.27))))
          (number "17" (effects (font (size 1.27 1.27))))
        )
        (pin bidirectional line (at 24.13 -22.86 180) (length 2.54)
          (name "DATA[6]" (effects (font (size 1.27 1.27))))
          (number "18" (effects (font (size 1.27 1.27))))
        )
        (pin bidirectional line (at 24.13 -20.32 180) (length 2.54)
          (name "DATA[5]" (effects (font (size 1.27 1.27))))
          (number "19" (effects (font (size 1.27 1.27))))
        )
        (pin passive line (at 0 -43.18 0) (length 2.54) hide
          (name "GND" (effects (font (size 1.27 1.27))))
          (number "2" (effects (font (size 1.27 1.27))))
        )
        (pin bidirectional line (at 24.13 -17.78 180) (length 2.54)
          (name "DATA[4]" (effects (font (size 1.27 1.27))))
          (number "20" (effects (font (size 1.27 1.27))))
        )
        (pin bidirectional line (at 24.13 -15.24 180) (length 2.54)
          (name "DATA[3]" (effects (font (size 1.27 1.27))))
          (number "21" (effects (font (size 1.27 1.27))))
        )
        (pin bidirectional line (at 24.13 -12.7 180) (length 2.54)
          (name "DATA[2]" (effects (font (size 1.27 1.27))))
          (number "22" (effects (font (size 1.27 1.27))))
        )
        (pin bidirectional line (at 24.13 -10.16 180) (length 2.54)
          (name "DATA[1]" (effects (font (size 1.27 1.27))))
          (number "23" (effects (font (size 1.27 1.27))))
        )
        (pin bidirectional line (at 24.13 -7.62 180) (length 2.54)
          (name "DATA[0]" (effects (font (size 1.27 1.27))))
          (number "24" (effects (font (size 1.27 1.27))))
        )
        (pin passive line (at 0 0 0) (length 2.54) hide
          (name "VDD3.3" (effects (font (size 1.27 1.27))))
          (number "25" (effects (font (size 1.27 1.27))))
        )
        (pin passive line (at 24.13 0 180) (length 2.54) hide
          (name "VDD1.8" (effects (font (size 1.27 1.27))))
          (number "26" (effects (font (size 1.27 1.27))))
        )
        (pin output line (at 0 -34.29 0) (length 2.54)
          (name "XO" (effects (font (size 1.27 1.27))))
          (number "27" (effects (font (size 1.27 1.27))))
        )
        (pin input line (at 0 -36.83 0) (length 2.54)
          (name "XI" (effects (font (size 1.27 1.27))))
          (number "28" (effects (font (size 1.27 1.27))))
        )
        (pin power_in line (at 24.13 -2.54 180) (length 2.54)
          (name "VDDA1.8" (effects (font (size 1.27 1.27))))
          (number "29" (effects (font (size 1.27 1.27))))
        )
        (pin output line (at 0 -20.32 0) (length 2.54)
          (name "CPEN" (effects (font (size 1.27 1.27))))
          (number "3" (effects (font (size 1.27 1.27))))
        )
        (pin passive line (at 0 0 0) (length 2.54) hide
          (name "VDD3.3" (effects (font (size 1.27 1.27))))
          (number "30" (effects (font (size 1.27 1.27))))
        )
        (pin bidirectional line (at 0 -2.54 0) (length 2.54)
          (name "REG_EN" (effects (font (size 1.27 1.27))))
          (number "31" (effects (font (size 1.27 1.27))))
        )
        (pin bidirectional line (at 0 -40.64 0) (length 2.54)
          (name "RBIAS" (effects (font (size 1.27 1.27))))
          (number "32" (effects (font (size 1.27 1.27))))
        )
        (pin passive line (at 0 -43.18 0) (length 2.54) hide
          (name "EP" (effects (font (size 1.27 1.27))))
          (number "33" (effects (font (size 1.27 1.27))))
        )
        (pin bidirectional line (at 0 -17.78 0) (length 2.54)
          (name "VBUS" (effects (font (size 1.27 1.27))))
          (number "4" (effects (font (size 1.27 1.27))))
        )
        (pin input line (at 0 -15.24 0) (length 2.54)
          (name "ID" (effects (font (size 1.27 1.27))))
          (number "5" (effects (font (size 1.27 1.27))))
        )
        (pin power_in line (at 0 0 0) (length 2.54)
          (name "VDD3.3" (effects (font (size 1.27 1.27))))
          (number "6" (effects (font (size 1.27 1.27))))
        )
        (pin bidirectional line (at 0 -10.16 0) (length 2.54)
          (name "DP" (effects (font (size 1.27 1.27))))
          (number "7" (effects (font (size 1.27 1.27))))
        )
        (pin bidirectional line (at 0 -7.62 0) (length 2.54)
          (name "DM" (effects (font (size 1.27 1.27))))
          (number "8" (effects (font (size 1.27 1.27))))
        )
        (pin input line (at 24.13 -40.64 180) (length 2.54)
          (name "RESET" (effects (font (size 1.27 1.27))))
          (number "9" (effects (font (size 1.27 1.27))))
        )
      )
    )
	(symbol "antmicroLogicTranslatorsLevelShifters:NVT2008BQ,115" (pin_names (offset 1.016)) (in_bom yes) (on_board yes)
      (property "Reference" "U" (at 35.56 -2.54 0)
        (effects (font (size 1.27 1.27) (thickness 0.15)) (justify left bottom))
      )
      (property "Value" "NVT2008BQ,115" (at 35.56 -5.08 0)
        (effects (font (size 1.27 1.27) (thickness 0.15)) (justify left bottom) hide)
      )
      (property "Footprint" "antmicro-footprints:VQFN-20_1EP_4.5x2.5mm_P0.5mm" (at 35.56 -7.62 0)
        (effects (font (size 1.27 1.27) (thickness 0.15)) (justify left bottom) hide)
      )
      (property "Datasheet" "https://www.nxp.com/docs/en/data-sheet/NVT2008_NVT2010.pdf" (at 35.56 -10.16 0)
        (effects (font (size 1.27 1.27) (thickness 0.15)) (justify left bottom) hide)
      )
      (property "MPN" "NVT2008BQ,115" (at 35.56 -12.7 0)
        (effects (font (size 1.27 1.27) (thickness 0.15)) (justify left bottom))
      )
      (property "Manufacturer" "NXP" (at 35.56 -15.24 0)
        (effects (font (size 1.27 1.27) (thickness 0.15)) (justify left bottom) hide)
      )
      (property "Author" "Antmicro" (at 35.56 -17.78 0)
        (effects (font (size 1.27 1.27) (thickness 0.15)) (justify left bottom) hide)
      )
      (property "License" "Apache-2.0" (at 35.56 -20.32 0)
        (effects (font (size 1.27 1.27) (thickness 0.15)) (justify left bottom) hide)
      )
      (property "ki_keywords" "SMT, LEVEL-SHIFTER, IC, LOGIC" (at 0 0 0)
        (effects (font (size 1.27 1.27)) hide)
      )
      (property "ki_description" "Bidirectional Voltage Level Translator, 8 Inputs, 1.5ns, 1.8V to 5.5V, DHVQFN-20" (at 0 0 0)
        (effects (font (size 1.27 1.27)) hide)
      )
      (symbol "NVT2008BQ,115_0_1"
        (rectangle (start 2.54 2.54) (end 17.78 -34.29)
          (stroke (width 0) (type default))
          (fill (type background))
        )
      )
      (symbol "NVT2008BQ,115_1_1"
        (pin power_in line (at 0 -31.75 0) (length 2.54)
          (name "GND" (effects (font (size 1.27 1.27))))
          (number "1" (effects (font (size 1.27 1.27))))
        )
        (pin bidirectional line (at 0 -25.4 0) (length 2.54)
          (name "A8" (effects (font (size 1.27 1.27))))
          (number "10" (effects (font (size 1.27 1.27))))
        )
        (pin bidirectional line (at 20.32 -25.4 180) (length 2.54)
          (name "B8" (effects (font (size 1.27 1.27))))
          (number "11" (effects (font (size 1.27 1.27))))
        )
        (pin bidirectional line (at 20.32 -22.86 180) (length 2.54)
          (name "B7" (effects (font (size 1.27 1.27))))
          (number "12" (effects (font (size 1.27 1.27))))
        )
        (pin bidirectional line (at 20.32 -20.32 180) (length 2.54)
          (name "B6" (effects (font (size 1.27 1.27))))
          (number "13" (effects (font (size 1.27 1.27))))
        )
        (pin bidirectional line (at 20.32 -17.78 180) (length 2.54)
          (name "B5" (effects (font (size 1.27 1.27))))
          (number "14" (effects (font (size 1.27 1.27))))
        )
        (pin bidirectional line (at 20.32 -15.24 180) (length 2.54)
          (name "B4" (effects (font (size 1.27 1.27))))
          (number "15" (effects (font (size 1.27 1.27))))
        )
        (pin bidirectional line (at 20.32 -12.7 180) (length 2.54)
          (name "B3" (effects (font (size 1.27 1.27))))
          (number "16" (effects (font (size 1.27 1.27))))
        )
        (pin bidirectional line (at 20.32 -10.16 180) (length 2.54)
          (name "B2" (effects (font (size 1.27 1.27))))
          (number "17" (effects (font (size 1.27 1.27))))
        )
        (pin bidirectional line (at 20.32 -7.62 180) (length 2.54)
          (name "B1" (effects (font (size 1.27 1.27))))
          (number "18" (effects (font (size 1.27 1.27))))
        )
        (pin power_in line (at 20.32 0 180) (length 2.54)
          (name "VREFB" (effects (font (size 1.27 1.27))))
          (number "19" (effects (font (size 1.27 1.27))))
        )
        (pin power_in line (at 0 0 0) (length 2.54)
          (name "VREFA" (effects (font (size 1.27 1.27))))
          (number "2" (effects (font (size 1.27 1.27))))
        )
        (pin input line (at 20.32 -2.54 180) (length 2.54)
          (name "EN" (effects (font (size 1.27 1.27))))
          (number "20" (effects (font (size 1.27 1.27))))
        )
        (pin power_in line (at 0 -29.21 0) (length 2.54)
          (name "EP" (effects (font (size 1.27 1.27))))
          (number "21" (effects (font (size 1.27 1.27))))
        )
        (pin bidirectional line (at 0 -7.62 0) (length 2.54)
          (name "A1" (effects (font (size 1.27 1.27))))
          (number "3" (effects (font (size 1.27 1.27))))
        )
        (pin bidirectional line (at 0 -10.16 0) (length 2.54)
          (name "A2" (effects (font (size 1.27 1.27))))
          (number "4" (effects (font (size 1.27 1.27))))
        )
        (pin bidirectional line (at 0 -12.7 0) (length 2.54)
          (name "A3" (effects (font (size 1.27 1.27))))
          (number "5" (effects (font (size 1.27 1.27))))
        )
        (pin bidirectional line (at 0 -15.24 0) (length 2.54)
          (name "A4" (effects (font (size 1.27 1.27))))
          (number "6" (effects (font (size 1.27 1.27))))
        )
        (pin bidirectional line (at 0 -17.78 0) (length 2.54)
          (name "A5" (effects (font (size 1.27 1.27))))
          (number "7" (effects (font (size 1.27 1.27))))
        )
        (pin bidirectional line (at 0 -20.32 0) (length 2.54)
          (name "A6" (effects (font (size 1.27 1.27))))
          (number "8" (effects (font (size 1.27 1.27))))
        )
        (pin bidirectional line (at 0 -22.86 0) (length 2.54)
          (name "A7" (effects (font (size 1.27 1.27))))
          (number "9" (effects (font (size 1.27 1.27))))
        )
      )
    )
	(symbol "antmicroMechanicalParts:Spacer_Drill3.7mm_H2.5mm_9774025151R" (in_bom yes) (on_board yes)
      (property "Reference" "H" (at 22.86 -2.54 0)
        (effects (font (size 1.27 1.27) (thickness 0.15)) (justify left bottom))
      )
      (property "Value" "Spacer_Drill3.7mm_H2.5mm_9774025151R" (at 22.86 -5.08 0)
        (effects (font (size 1.27 1.27) (thickness 0.15)) (justify left bottom))
      )
      (property "Footprint" "antmicro-footprints:Spacer_Drill3.7mm_H2.5mm_9774025151R" (at 22.86 -7.62 0)
        (effects (font (size 1.27 1.27) (thickness 0.15)) (justify left bottom) hide)
      )
      (property "Datasheet" "https://www.we-online.com/components/products/datasheet/9774025151R.pdf" (at 22.86 -10.16 0)
        (effects (font (size 1.27 1.27) (thickness 0.15)) (justify left bottom) hide)
      )
      (property "Manufacturer" "Würth Elektronik" (at 22.86 -12.7 0)
        (effects (font (size 1.27 1.27) (thickness 0.15)) (justify left bottom) hide)
      )
      (property "MPN" "9774025151R" (at 22.86 -15.24 0)
        (effects (font (size 1.27 1.27) (thickness 0.15)) (justify left bottom) hide)
      )
      (property "Author" "Antmicro" (at 22.86 -17.78 0)
        (effects (font (size 1.27 1.27) (thickness 0.15)) (justify left bottom) hide)
      )
      (property "License" "Apache-2.0" (at 22.86 -20.32 0)
        (effects (font (size 1.27 1.27) (thickness 0.15)) (justify left bottom) hide)
      )
      (property "ki_keywords" "MECHANICAL, SPACER" (at 0 0 0)
        (effects (font (size 1.27 1.27)) hide)
      )
      (property "ki_description" "Spacer, SMT, Non Stop, Steel, Swage Round, 5.1 mm x 2.5 mm, M2.5 Thread, WA-SMSI Series" (at 0 0 0)
        (effects (font (size 1.27 1.27)) hide)
      )
      (symbol "Spacer_Drill3.7mm_H2.5mm_9774025151R_1_1"
        (rectangle (start 2.54 -2.54) (end 7.62 2.54)
          (stroke (width 0.254) (type default))
          (fill (type background))
        )
        (rectangle (start 3.81 -1.27) (end 6.35 1.27)
          (stroke (width 0.254) (type default))
          (fill (type background))
        )
        (pin passive line (at 0 0 0) (length 2.54)
          (name "~" (effects (font (size 1.27 1.27))))
          (number "1" (effects (font (size 1.27 1.27))))
        )
      )
    )
	(symbol "antmicroMechanicalParts:Spacer_Drill3.7mm_H4mm_9774040151R" (in_bom yes) (on_board yes)
      (property "Reference" "H" (at 22.86 -2.54 0)
        (effects (font (size 1.27 1.27) (thickness 0.15)) (justify left bottom))
      )
      (property "Value" "Spacer_Drill3.7mm_H4mm_9774040151R" (at 22.86 -5.08 0)
        (effects (font (size 1.27 1.27) (thickness 0.15)) (justify left bottom))
      )
      (property "Footprint" "antmicro-footprints:Spacer_Drill3.7mm_H4mm_9774040151R" (at 22.86 -7.62 0)
        (effects (font (size 1.27 1.27) (thickness 0.15)) (justify left bottom) hide)
      )
      (property "Datasheet" "https://www.we-online.com/components/products/datasheet/9774040151R.pdf" (at 22.86 -10.16 0)
        (effects (font (size 1.27 1.27) (thickness 0.15)) (justify left bottom) hide)
      )
      (property "Manufacturer" "Würth Elektronik" (at 22.86 -12.7 0)
        (effects (font (size 1.27 1.27) (thickness 0.15)) (justify left bottom) hide)
      )
      (property "MPN" "9774040151R" (at 22.86 -15.24 0)
        (effects (font (size 1.27 1.27) (thickness 0.15)) (justify left bottom) hide)
      )
      (property "Author" "Antmicro" (at 22.86 -17.78 0)
        (effects (font (size 1.27 1.27) (thickness 0.15)) (justify left bottom) hide)
      )
      (property "License" "Apache-2.0" (at 22.86 -20.32 0)
        (effects (font (size 1.27 1.27) (thickness 0.15)) (justify left bottom) hide)
      )
      (property "ki_keywords" "SPACER" (at 0 0 0)
        (effects (font (size 1.27 1.27)) hide)
      )
      (property "ki_description" "Round Standoff Threaded M2.5x0.45 Steel 0.157\" (4.00mm)" (at 0 0 0)
        (effects (font (size 1.27 1.27)) hide)
      )
      (symbol "Spacer_Drill3.7mm_H4mm_9774040151R_1_1"
        (rectangle (start 2.54 -2.54) (end 7.62 2.54)
          (stroke (width 0.254) (type default))
          (fill (type background))
        )
        (rectangle (start 3.81 -1.27) (end 6.35 1.27)
          (stroke (width 0.254) (type default))
          (fill (type background))
        )
        (pin passive line (at 0 0 0) (length 2.54)
          (name "~" (effects (font (size 1.27 1.27))))
          (number "1" (effects (font (size 1.27 1.27))))
        )
      )
    )
	(symbol "antmicroMechanicalParts:antmicro_logo" (in_bom no) (on_board yes)
      (property "Reference" "N" (at 15.24 -5.08 0)
        (effects (font (size 1.27 1.27) (thickness 0.15)) (justify left bottom))
      )
      (property "Value" "antmicro_logo" (at 15.24 -7.62 0)
        (effects (font (size 1.27 1.27) (thickness 0.15)) (justify left bottom))
      )
      (property "Footprint" "antmicro-footprints:antmicro-logo" (at 15.24 -10.16 0)
        (effects (font (size 1.27 1.27) (thickness 0.15)) (justify left bottom) hide)
      )
      (property "Datasheet" "" (at 15.24 -12.7 0)
        (effects (font (size 1.27 1.27) (thickness 0.15)) (justify left bottom) hide)
      )
      (property "MPN" "" (at 0 0 0)
        (effects (font (size 1.27 1.27)))
      )
      (property "Manufacturer" "" (at 15.24 -20.32 0)
        (effects (font (size 1.27 1.27) (thickness 0.15)) (justify left bottom) hide)
      )
      (property "Author" "Antmicro" (at 15.24 -15.24 0)
        (effects (font (size 1.27 1.27) (thickness 0.15)) (justify left bottom) hide)
      )
      (property "License" "Apache-2.0" (at 15.24 -17.78 0)
        (effects (font (size 1.27 1.27) (thickness 0.15)) (justify left bottom) hide)
      )
      (property "ki_description" "Mechanical part" (at 0 0 0)
        (effects (font (size 1.27 1.27)) hide)
      )
      (symbol "antmicro_logo_1_1"
        (text "Logo" (at 0 0 0)
          (effects (font (size 1.27 1.27) (thickness 0.15)) (justify left bottom))
        )
      )
    )
	(symbol "antmicroMechanicalParts:oshw_logo" (in_bom no) (on_board yes)
      (property "Reference" "N" (at 15.24 -5.08 0)
        (effects (font (size 1.27 1.27) (thickness 0.15)) (justify left bottom))
      )
      (property "Value" "oshw_logo" (at 15.24 -7.62 0)
        (effects (font (size 1.27 1.27) (thickness 0.15)) (justify left bottom))
      )
      (property "Footprint" "antmicro-footprints:oshw-logo" (at 15.24 -10.16 0)
        (effects (font (size 1.27 1.27) (thickness 0.15)) (justify left bottom) hide)
      )
      (property "Datasheet" "" (at 15.24 -12.7 0)
        (effects (font (size 1.27 1.27) (thickness 0.15)) (justify left bottom) hide)
      )
      (property "Author" "Antmicro" (at 15.24 -15.24 0)
        (effects (font (size 1.27 1.27) (thickness 0.15)) (justify left bottom) hide)
      )
      (property "License" "Apache-2.0" (at 15.24 -17.78 0)
        (effects (font (size 1.27 1.27) (thickness 0.15)) (justify left bottom) hide)
      )
      (property "MPN" "" (at 0 0 0)
        (effects (font (size 1.27 1.27)))
      )
      (property "Manufacturer" "" (at 15.24 -20.32 0)
        (effects (font (size 1.27 1.27) (thickness 0.15)) (justify left bottom) hide)
      )
      (property "ki_description" "Mechanical part" (at 0 0 0)
        (effects (font (size 1.27 1.27)) hide)
      )
      (symbol "oshw_logo_1_1"
        (text "Logo" (at 0 0 0)
          (effects (font (size 1.27 1.27) (thickness 0.15)) (justify left bottom))
        )
      )
    )
	(symbol "antmicroMemory:AS4C256M16D3" (pin_names (offset 1.016)) (in_bom yes) (on_board yes)
      (property "Reference" "U" (at 50.8 0 0)
        (effects (font (size 1.27 1.27) (thickness 0.15)) (justify left bottom))
      )
      (property "Value" "AS4C256M16D3" (at 50.8 -2.54 0)
        (effects (font (size 1.27 1.27) (thickness 0.15)) (justify left bottom) hide)
      )
      (property "Footprint" "antmicro-footprints:BGA-96_9.0x13.0mm_Layout2x3x16_P0.8mm" (at 50.8 -5.08 0)
        (effects (font (size 1.27 1.27) (thickness 0.15)) (justify left bottom) hide)
      )
      (property "Datasheet" "https://www.alliancememory.com/wp-content/uploads/pdf/ddr3/4GB-AS4C256M16D3.pdf" (at 50.8 -7.62 0)
        (effects (font (size 1.27 1.27) (thickness 0.15)) (justify left bottom) hide)
      )
      (property "Manufacturer" "Alliance Memory" (at 50.8 -10.16 0)
        (effects (font (size 1.27 1.27) (thickness 0.15)) (justify left bottom) hide)
      )
      (property "MPN" "AS4C256M16D3" (at 50.8 -12.7 0)
        (effects (font (size 1.27 1.27) (thickness 0.15)) (justify left bottom))
      )
      (property "Author" "Antmicro" (at 50.8 -15.24 0)
        (effects (font (size 1.27 1.27) (thickness 0.15)) (justify left bottom) hide)
      )
      (property "License" "Apache-2.0" (at 50.8 -17.78 0)
        (effects (font (size 1.27 1.27) (thickness 0.15)) (justify left bottom) hide)
      )
      (property "ki_keywords" "SMT, MEMORY, IC, DDR, SYNCHRONOUS" (at 0 0 0)
        (effects (font (size 1.27 1.27)) hide)
      )
      (property "ki_description" "SDRAM - DDR3 Memory IC 4Gbit Parallel 800 MHz 20 ns 96-FBGA (9x13)" (at 0 0 0)
        (effects (font (size 1.27 1.27)) hide)
      )
      (symbol "AS4C256M16D3_1_1"
        (rectangle (start 2.54 2.54) (end 33.02 -88.9)
          (stroke (width 0.254) (type default))
          (fill (type background))
        )
        (text "256Mx16 DDR3" (at 17.78 -44.45 900)
          (effects (font (size 1.27 1.27) (thickness 0.15)) (justify left bottom))
        )
        (pin power_in line (at 0 -2.54 0) (length 2.54)
          (name "VDDQ" (effects (font (size 1.27 1.27))))
          (number "A1" (effects (font (size 1.27 1.27))))
        )
        (pin bidirectional line (at 35.56 -53.34 180) (length 2.54)
          (name "DQ13" (effects (font (size 1.27 1.27))))
          (number "A2" (effects (font (size 1.27 1.27))))
        )
        (pin bidirectional line (at 35.56 -58.42 180) (length 2.54)
          (name "DQ15" (effects (font (size 1.27 1.27))))
          (number "A3" (effects (font (size 1.27 1.27))))
        )
        (pin bidirectional line (at 35.56 -50.8 180) (length 2.54)
          (name "DQ12" (effects (font (size 1.27 1.27))))
          (number "A7" (effects (font (size 1.27 1.27))))
        )
        (pin passive line (at 0 -2.54 0) (length 2.54) hide
          (name "VDDQ" (effects (font (size 1.27 1.27))))
          (number "A8" (effects (font (size 1.27 1.27))))
        )
        (pin power_in line (at 35.56 -83.82 180) (length 2.54)
          (name "VSS" (effects (font (size 1.27 1.27))))
          (number "A9" (effects (font (size 1.27 1.27))))
        )
        (pin power_in line (at 35.56 -86.36 180) (length 2.54)
          (name "VSSQ" (effects (font (size 1.27 1.27))))
          (number "B1" (effects (font (size 1.27 1.27))))
        )
        (pin power_in line (at 0 0 0) (length 2.54)
          (name "VDD" (effects (font (size 1.27 1.27))))
          (number "B2" (effects (font (size 1.27 1.27))))
        )
        (pin passive line (at 35.56 -83.82 180) (length 2.54) hide
          (name "VSS" (effects (font (size 1.27 1.27))))
          (number "B3" (effects (font (size 1.27 1.27))))
        )
        (pin bidirectional line (at 35.56 -15.24 180) (length 2.54)
          (name "~{UDQS}" (effects (font (size 1.27 1.27))))
          (number "B7" (effects (font (size 1.27 1.27))))
        )
        (pin bidirectional line (at 35.56 -55.88 180) (length 2.54)
          (name "DQ14" (effects (font (size 1.27 1.27))))
          (number "B8" (effects (font (size 1.27 1.27))))
        )
        (pin passive line (at 35.56 -86.36 180) (length 2.54) hide
          (name "VSSQ" (effects (font (size 1.27 1.27))))
          (number "B9" (effects (font (size 1.27 1.27))))
        )
        (pin passive line (at 0 -2.54 0) (length 2.54) hide
          (name "VDDQ" (effects (font (size 1.27 1.27))))
          (number "C1" (effects (font (size 1.27 1.27))))
        )
        (pin bidirectional line (at 35.56 -48.26 180) (length 2.54)
          (name "DQ11" (effects (font (size 1.27 1.27))))
          (number "C2" (effects (font (size 1.27 1.27))))
        )
        (pin bidirectional line (at 35.56 -43.18 180) (length 2.54)
          (name "DQ9" (effects (font (size 1.27 1.27))))
          (number "C3" (effects (font (size 1.27 1.27))))
        )
        (pin bidirectional line (at 35.56 -12.7 180) (length 2.54)
          (name "UDQS" (effects (font (size 1.27 1.27))))
          (number "C7" (effects (font (size 1.27 1.27))))
        )
        (pin bidirectional line (at 35.56 -45.72 180) (length 2.54)
          (name "DQ10" (effects (font (size 1.27 1.27))))
          (number "C8" (effects (font (size 1.27 1.27))))
        )
        (pin passive line (at 0 -2.54 0) (length 2.54) hide
          (name "VDDQ" (effects (font (size 1.27 1.27))))
          (number "C9" (effects (font (size 1.27 1.27))))
        )
        (pin passive line (at 35.56 -86.36 180) (length 2.54) hide
          (name "VSSQ" (effects (font (size 1.27 1.27))))
          (number "D1" (effects (font (size 1.27 1.27))))
        )
        (pin passive line (at 0 -2.54 0) (length 2.54) hide
          (name "VDDQ" (effects (font (size 1.27 1.27))))
          (number "D2" (effects (font (size 1.27 1.27))))
        )
        (pin input line (at 0 -27.94 0) (length 2.54)
          (name "UDM" (effects (font (size 1.27 1.27))))
          (number "D3" (effects (font (size 1.27 1.27))))
        )
        (pin bidirectional line (at 35.56 -40.64 180) (length 2.54)
          (name "DQ8" (effects (font (size 1.27 1.27))))
          (number "D7" (effects (font (size 1.27 1.27))))
        )
        (pin passive line (at 35.56 -86.36 180) (length 2.54) hide
          (name "VSSQ" (effects (font (size 1.27 1.27))))
          (number "D8" (effects (font (size 1.27 1.27))))
        )
        (pin passive line (at 0 0 0) (length 2.54) hide
          (name "VDD" (effects (font (size 1.27 1.27))))
          (number "D9" (effects (font (size 1.27 1.27))))
        )
        (pin passive line (at 35.56 -83.82 180) (length 2.54) hide
          (name "VSS" (effects (font (size 1.27 1.27))))
          (number "E1" (effects (font (size 1.27 1.27))))
        )
        (pin passive line (at 35.56 -86.36 180) (length 2.54) hide
          (name "VSSQ" (effects (font (size 1.27 1.27))))
          (number "E2" (effects (font (size 1.27 1.27))))
        )
        (pin bidirectional line (at 35.56 -20.32 180) (length 2.54)
          (name "DQ0" (effects (font (size 1.27 1.27))))
          (number "E3" (effects (font (size 1.27 1.27))))
        )
        (pin input line (at 0 -25.4 0) (length 2.54)
          (name "LDM" (effects (font (size 1.27 1.27))))
          (number "E7" (effects (font (size 1.27 1.27))))
        )
        (pin passive line (at 35.56 -86.36 180) (length 2.54) hide
          (name "VSSQ" (effects (font (size 1.27 1.27))))
          (number "E8" (effects (font (size 1.27 1.27))))
        )
        (pin passive line (at 0 -2.54 0) (length 2.54) hide
          (name "VDDQ" (effects (font (size 1.27 1.27))))
          (number "E9" (effects (font (size 1.27 1.27))))
        )
        (pin passive line (at 0 -2.54 0) (length 2.54) hide
          (name "VDDQ" (effects (font (size 1.27 1.27))))
          (number "F1" (effects (font (size 1.27 1.27))))
        )
        (pin bidirectional line (at 35.56 -25.4 180) (length 2.54)
          (name "DQ2" (effects (font (size 1.27 1.27))))
          (number "F2" (effects (font (size 1.27 1.27))))
        )
        (pin bidirectional line (at 35.56 -7.62 180) (length 2.54)
          (name "LDQS" (effects (font (size 1.27 1.27))))
          (number "F3" (effects (font (size 1.27 1.27))))
        )
        (pin bidirectional line (at 35.56 -22.86 180) (length 2.54)
          (name "DQ1" (effects (font (size 1.27 1.27))))
          (number "F7" (effects (font (size 1.27 1.27))))
        )
        (pin bidirectional line (at 35.56 -27.94 180) (length 2.54)
          (name "DQ3" (effects (font (size 1.27 1.27))))
          (number "F8" (effects (font (size 1.27 1.27))))
        )
        (pin passive line (at 35.56 -86.36 180) (length 2.54) hide
          (name "VSSQ" (effects (font (size 1.27 1.27))))
          (number "F9" (effects (font (size 1.27 1.27))))
        )
        (pin passive line (at 35.56 -86.36 180) (length 2.54) hide
          (name "VSSQ" (effects (font (size 1.27 1.27))))
          (number "G1" (effects (font (size 1.27 1.27))))
        )
        (pin bidirectional line (at 35.56 -35.56 180) (length 2.54)
          (name "DQ6" (effects (font (size 1.27 1.27))))
          (number "G2" (effects (font (size 1.27 1.27))))
        )
        (pin bidirectional line (at 35.56 -10.16 180) (length 2.54)
          (name "~{LDQS}" (effects (font (size 1.27 1.27))))
          (number "G3" (effects (font (size 1.27 1.27))))
        )
        (pin passive line (at 0 0 0) (length 2.54) hide
          (name "VDD" (effects (font (size 1.27 1.27))))
          (number "G7" (effects (font (size 1.27 1.27))))
        )
        (pin passive line (at 35.56 -83.82 180) (length 2.54) hide
          (name "VSS" (effects (font (size 1.27 1.27))))
          (number "G8" (effects (font (size 1.27 1.27))))
        )
        (pin passive line (at 35.56 -86.36 180) (length 2.54) hide
          (name "VSSQ" (effects (font (size 1.27 1.27))))
          (number "G9" (effects (font (size 1.27 1.27))))
        )
        (pin power_in line (at 35.56 0 180) (length 2.54)
          (name "VREF_DQ" (effects (font (size 1.27 1.27))))
          (number "H1" (effects (font (size 1.27 1.27))))
        )
        (pin passive line (at 0 -2.54 0) (length 2.54) hide
          (name "VDDQ" (effects (font (size 1.27 1.27))))
          (number "H2" (effects (font (size 1.27 1.27))))
        )
        (pin bidirectional line (at 35.56 -30.48 180) (length 2.54)
          (name "DQ4" (effects (font (size 1.27 1.27))))
          (number "H3" (effects (font (size 1.27 1.27))))
        )
        (pin bidirectional line (at 35.56 -38.1 180) (length 2.54)
          (name "DQ7" (effects (font (size 1.27 1.27))))
          (number "H7" (effects (font (size 1.27 1.27))))
        )
        (pin bidirectional line (at 35.56 -33.02 180) (length 2.54)
          (name "DQ5" (effects (font (size 1.27 1.27))))
          (number "H8" (effects (font (size 1.27 1.27))))
        )
        (pin passive line (at 0 -2.54 0) (length 2.54) hide
          (name "VDDQ" (effects (font (size 1.27 1.27))))
          (number "H9" (effects (font (size 1.27 1.27))))
        )
        (pin no_connect line (at 15.24 -88.9 90) (length 2.54) hide
          (name "J1" (effects (font (size 1.27 1.27))))
          (number "J1" (effects (font (size 1.27 1.27))))
        )
        (pin passive line (at 35.56 -62.23 180) (length 2.54)
          (name "NC/ODT1" (effects (font (size 1.27 1.27))))
          (number "J1" (effects (font (size 1.27 1.27))))
        )
        (pin passive line (at 35.56 -83.82 180) (length 2.54) hide
          (name "VSS" (effects (font (size 1.27 1.27))))
          (number "J2" (effects (font (size 1.27 1.27))))
        )
        (pin input line (at 0 -10.16 0) (length 2.54)
          (name "~{RAS}" (effects (font (size 1.27 1.27))))
          (number "J3" (effects (font (size 1.27 1.27))))
        )
        (pin input clock (at 0 -35.56 0) (length 2.54)
          (name "CK" (effects (font (size 1.27 1.27))))
          (number "J7" (effects (font (size 1.27 1.27))))
        )
        (pin passive line (at 35.56 -83.82 180) (length 2.54) hide
          (name "VSS" (effects (font (size 1.27 1.27))))
          (number "J8" (effects (font (size 1.27 1.27))))
        )
        (pin no_connect line (at 22.86 -88.9 90) (length 2.54) hide
          (name "J9" (effects (font (size 1.27 1.27))))
          (number "J9" (effects (font (size 1.27 1.27))))
        )
        (pin passive line (at 35.56 -64.77 180) (length 2.54)
          (name "NC/CKE1" (effects (font (size 1.27 1.27))))
          (number "J9" (effects (font (size 1.27 1.27))))
        )
        (pin input line (at 0 -22.86 0) (length 2.54)
          (name "ODT" (effects (font (size 1.27 1.27))))
          (number "K1" (effects (font (size 1.27 1.27))))
        )
        (pin passive line (at 0 0 0) (length 2.54) hide
          (name "VDD" (effects (font (size 1.27 1.27))))
          (number "K2" (effects (font (size 1.27 1.27))))
        )
        (pin input line (at 0 -12.7 0) (length 2.54)
          (name "~{CAS}" (effects (font (size 1.27 1.27))))
          (number "K3" (effects (font (size 1.27 1.27))))
        )
        (pin input clock (at 0 -38.1 0) (length 2.54)
          (name "~{CK}" (effects (font (size 1.27 1.27))))
          (number "K7" (effects (font (size 1.27 1.27))))
        )
        (pin passive line (at 0 0 0) (length 2.54) hide
          (name "VDD" (effects (font (size 1.27 1.27))))
          (number "K8" (effects (font (size 1.27 1.27))))
        )
        (pin input line (at 0 -33.02 0) (length 2.54)
          (name "CKE" (effects (font (size 1.27 1.27))))
          (number "K9" (effects (font (size 1.27 1.27))))
        )
        (pin no_connect line (at 17.78 -88.9 90) (length 2.54) hide
          (name "L1" (effects (font (size 1.27 1.27))))
          (number "L1" (effects (font (size 1.27 1.27))))
        )
        (pin passive line (at 35.56 -67.31 180) (length 2.54)
          (name "NC/~{CS1}" (effects (font (size 1.27 1.27))))
          (number "L1" (effects (font (size 1.27 1.27))))
        )
        (pin input line (at 0 -17.78 0) (length 2.54)
          (name "~{CS}" (effects (font (size 1.27 1.27))))
          (number "L2" (effects (font (size 1.27 1.27))))
        )
        (pin input line (at 0 -15.24 0) (length 2.54)
          (name "~{WE}" (effects (font (size 1.27 1.27))))
          (number "L3" (effects (font (size 1.27 1.27))))
        )
        (pin input line (at 0 -68.58 0) (length 2.54)
          (name "A10/AP" (effects (font (size 1.27 1.27))))
          (number "L7" (effects (font (size 1.27 1.27))))
        )
        (pin passive line (at 35.56 -76.2 180) (length 2.54)
          (name "ZQ" (effects (font (size 1.27 1.27))))
          (number "L8" (effects (font (size 1.27 1.27))))
        )
        (pin no_connect line (at 25.4 -88.9 90) (length 2.54) hide
          (name "L9" (effects (font (size 1.27 1.27))))
          (number "L9" (effects (font (size 1.27 1.27))))
        )
        (pin passive line (at 35.56 -69.85 180) (length 2.54)
          (name "NC/ZQ1" (effects (font (size 1.27 1.27))))
          (number "L9" (effects (font (size 1.27 1.27))))
        )
        (pin passive line (at 35.56 -83.82 180) (length 2.54) hide
          (name "VSS" (effects (font (size 1.27 1.27))))
          (number "M1" (effects (font (size 1.27 1.27))))
        )
        (pin input line (at 0 -81.28 0) (length 2.54)
          (name "BA0" (effects (font (size 1.27 1.27))))
          (number "M2" (effects (font (size 1.27 1.27))))
        )
        (pin input line (at 0 -86.36 0) (length 2.54)
          (name "BA2" (effects (font (size 1.27 1.27))))
          (number "M3" (effects (font (size 1.27 1.27))))
        )
        (pin no_connect line (at 12.7 -88.9 90) (length 2.54) hide
          (name "M7" (effects (font (size 1.27 1.27))))
          (number "M7" (effects (font (size 1.27 1.27))))
        )
        (pin passive line (at 35.56 -72.39 180) (length 2.54)
          (name "NC/A15" (effects (font (size 1.27 1.27))))
          (number "M7" (effects (font (size 1.27 1.27))))
        )
        (pin power_in line (at 35.56 -2.54 180) (length 2.54)
          (name "VREF_CA" (effects (font (size 1.27 1.27))))
          (number "M8" (effects (font (size 1.27 1.27))))
        )
        (pin passive line (at 35.56 -83.82 180) (length 2.54) hide
          (name "VSS" (effects (font (size 1.27 1.27))))
          (number "M9" (effects (font (size 1.27 1.27))))
        )
        (pin passive line (at 0 0 0) (length 2.54) hide
          (name "VDD" (effects (font (size 1.27 1.27))))
          (number "N1" (effects (font (size 1.27 1.27))))
        )
        (pin input line (at 0 -50.8 0) (length 2.54)
          (name "A3" (effects (font (size 1.27 1.27))))
          (number "N2" (effects (font (size 1.27 1.27))))
        )
        (pin input line (at 0 -43.18 0) (length 2.54)
          (name "A0" (effects (font (size 1.27 1.27))))
          (number "N3" (effects (font (size 1.27 1.27))))
        )
        (pin input line (at 0 -73.66 0) (length 2.54)
          (name "A12/~{BC}" (effects (font (size 1.27 1.27))))
          (number "N7" (effects (font (size 1.27 1.27))))
        )
        (pin input line (at 0 -83.82 0) (length 2.54)
          (name "BA1" (effects (font (size 1.27 1.27))))
          (number "N8" (effects (font (size 1.27 1.27))))
        )
        (pin passive line (at 0 0 0) (length 2.54) hide
          (name "VDD" (effects (font (size 1.27 1.27))))
          (number "N9" (effects (font (size 1.27 1.27))))
        )
        (pin passive line (at 35.56 -83.82 180) (length 2.54) hide
          (name "VSS" (effects (font (size 1.27 1.27))))
          (number "P1" (effects (font (size 1.27 1.27))))
        )
        (pin input line (at 0 -55.88 0) (length 2.54)
          (name "A5" (effects (font (size 1.27 1.27))))
          (number "P2" (effects (font (size 1.27 1.27))))
        )
        (pin input line (at 0 -48.26 0) (length 2.54)
          (name "A2" (effects (font (size 1.27 1.27))))
          (number "P3" (effects (font (size 1.27 1.27))))
        )
        (pin input line (at 0 -45.72 0) (length 2.54)
          (name "A1" (effects (font (size 1.27 1.27))))
          (number "P7" (effects (font (size 1.27 1.27))))
        )
        (pin input line (at 0 -53.34 0) (length 2.54)
          (name "A4" (effects (font (size 1.27 1.27))))
          (number "P8" (effects (font (size 1.27 1.27))))
        )
        (pin passive line (at 35.56 -83.82 180) (length 2.54) hide
          (name "VSS" (effects (font (size 1.27 1.27))))
          (number "P9" (effects (font (size 1.27 1.27))))
        )
        (pin passive line (at 0 0 0) (length 2.54) hide
          (name "VDD" (effects (font (size 1.27 1.27))))
          (number "R1" (effects (font (size 1.27 1.27))))
        )
        (pin input line (at 0 -60.96 0) (length 2.54)
          (name "A7" (effects (font (size 1.27 1.27))))
          (number "R2" (effects (font (size 1.27 1.27))))
        )
        (pin input line (at 0 -66.04 0) (length 2.54)
          (name "A9" (effects (font (size 1.27 1.27))))
          (number "R3" (effects (font (size 1.27 1.27))))
        )
        (pin input line (at 0 -71.12 0) (length 2.54)
          (name "A11" (effects (font (size 1.27 1.27))))
          (number "R7" (effects (font (size 1.27 1.27))))
        )
        (pin input line (at 0 -58.42 0) (length 2.54)
          (name "A6" (effects (font (size 1.27 1.27))))
          (number "R8" (effects (font (size 1.27 1.27))))
        )
        (pin passive line (at 0 0 0) (length 2.54) hide
          (name "VDD" (effects (font (size 1.27 1.27))))
          (number "R9" (effects (font (size 1.27 1.27))))
        )
        (pin passive line (at 35.56 -83.82 180) (length 2.54) hide
          (name "VSS" (effects (font (size 1.27 1.27))))
          (number "T1" (effects (font (size 1.27 1.27))))
        )
        (pin input line (at 0 -7.62 0) (length 2.54)
          (name "~{RESET}" (effects (font (size 1.27 1.27))))
          (number "T2" (effects (font (size 1.27 1.27))))
        )
        (pin input line (at 0 -76.2 0) (length 2.54)
          (name "A13" (effects (font (size 1.27 1.27))))
          (number "T3" (effects (font (size 1.27 1.27))))
        )
        (pin input line (at 0 -78.74 0) (length 2.54)
          (name "A14" (effects (font (size 1.27 1.27))))
          (number "T7" (effects (font (size 1.27 1.27))))
        )
        (pin no_connect line (at 20.32 -88.9 90) (length 2.54) hide
          (name "T7" (effects (font (size 1.27 1.27))))
          (number "T7" (effects (font (size 1.27 1.27))))
        )
        (pin input line (at 0 -63.5 0) (length 2.54)
          (name "A8" (effects (font (size 1.27 1.27))))
          (number "T8" (effects (font (size 1.27 1.27))))
        )
        (pin passive line (at 35.56 -83.82 180) (length 2.54) hide
          (name "VSS" (effects (font (size 1.27 1.27))))
          (number "T9" (effects (font (size 1.27 1.27))))
        )
      )
    )
	(symbol "antmicroMemory:MTFC16GAPALNA-AIT" (pin_names (offset 1.016)) (in_bom yes) (on_board yes)
      (property "Reference" "U" (at 33.02 -2.54 0)
        (effects (font (size 1.27 1.27) (thickness 0.15)) (justify left bottom))
      )
      (property "Value" "MTFC16GAPALNA-AIT" (at 33.02 -5.08 0)
        (effects (font (size 1.27 1.27) (thickness 0.15)) (justify left bottom) hide)
      )
      (property "Footprint" "antmicro-footprints:BGA-170-100_18x14mm_Layout17x10_P1mm" (at 33.02 -7.62 0)
        (effects (font (size 1.27 1.27) (thickness 0.15)) (justify left bottom) hide)
      )
      (property "Datasheet" "https://www.mouser.com/datasheet/2/671/micron_technology_mict-s-a0006806196-1-1759129.pdf" (at 33.02 -10.16 0)
        (effects (font (size 1.27 1.27) (thickness 0.15)) (justify left bottom) hide)
      )
      (property "Manufacturer" "Micron Technology" (at 33.02 -12.7 0)
        (effects (font (size 1.27 1.27) (thickness 0.15)) (justify left bottom) hide)
      )
      (property "MPN" "MTFC16GAPALNA-AIT" (at 33.02 -15.24 0)
        (effects (font (size 1.27 1.27) (thickness 0.15)) (justify left bottom))
      )
      (property "Author" "Antmicro" (at 33.02 -17.78 0)
        (effects (font (size 1.27 1.27) (thickness 0.15)) (justify left bottom) hide)
      )
      (property "License" "Apache-2.0" (at 33.02 -20.32 0)
        (effects (font (size 1.27 1.27) (thickness 0.15)) (justify left bottom) hide)
      )
      (property "ki_keywords" "SMT, FLASH, IC" (at 0 0 0)
        (effects (font (size 1.27 1.27)) hide)
      )
      (property "ki_description" "Managed NAND Flash Serial e-MMC 3.3V 128G-bit 128G/32G/16G x 1/4-bit/8-bit Automotive AEC-Q100 100-Pin TBGA Tray" (at 0 0 0)
        (effects (font (size 1.27 1.27)) hide)
      )
      (symbol "MTFC16GAPALNA-AIT_0_0"
        (rectangle (start 2.54 2.54) (end 17.78 -27.94)
          (stroke (width 0.254) (type default))
          (fill (type background))
        )
        (pin no_connect line (at 7.62 1.27 0) (length 2.54) hide
          (name "NC" (effects (font (size 1.27 1.27))))
          (number "A1" (effects (font (size 1.27 1.27))))
        )
        (pin no_connect line (at 7.62 -6.35 0) (length 2.54) hide
          (name "NC" (effects (font (size 1.27 1.27))))
          (number "A10" (effects (font (size 1.27 1.27))))
        )
        (pin no_connect line (at 7.62 -1.27 0) (length 2.54) hide
          (name "NC" (effects (font (size 1.27 1.27))))
          (number "A2" (effects (font (size 1.27 1.27))))
        )
        (pin no_connect line (at 7.62 -3.81 0) (length 2.54) hide
          (name "NC" (effects (font (size 1.27 1.27))))
          (number "A9" (effects (font (size 1.27 1.27))))
        )
        (pin no_connect line (at 7.62 -8.89 0) (length 2.54) hide
          (name "NC" (effects (font (size 1.27 1.27))))
          (number "B1" (effects (font (size 1.27 1.27))))
        )
        (pin no_connect line (at 7.62 -11.43 0) (length 2.54) hide
          (name "NC" (effects (font (size 1.27 1.27))))
          (number "B10" (effects (font (size 1.27 1.27))))
        )
        (pin no_connect line (at 12.7 -8.89 0) (length 2.54) hide
          (name "VSF1" (effects (font (size 1.27 1.27))))
          (number "D2" (effects (font (size 1.27 1.27))))
        )
        (pin no_connect line (at 12.7 -11.43 0) (length 2.54) hide
          (name "VSF2" (effects (font (size 1.27 1.27))))
          (number "D3" (effects (font (size 1.27 1.27))))
        )
        (pin no_connect line (at 12.7 -13.97 0) (length 2.54) hide
          (name "VSF3" (effects (font (size 1.27 1.27))))
          (number "D4" (effects (font (size 1.27 1.27))))
        )
        (pin no_connect line (at 12.7 -16.51 0) (length 2.54) hide
          (name "VSF4" (effects (font (size 1.27 1.27))))
          (number "D5" (effects (font (size 1.27 1.27))))
        )
        (pin no_connect line (at 12.7 -19.05 0) (length 2.54) hide
          (name "VSF5" (effects (font (size 1.27 1.27))))
          (number "D6" (effects (font (size 1.27 1.27))))
        )
        (pin no_connect line (at 12.7 -21.59 0) (length 2.54) hide
          (name "VSF6" (effects (font (size 1.27 1.27))))
          (number "D7" (effects (font (size 1.27 1.27))))
        )
        (pin no_connect line (at 12.7 -24.13 0) (length 2.54) hide
          (name "VSF7" (effects (font (size 1.27 1.27))))
          (number "D8" (effects (font (size 1.27 1.27))))
        )
        (pin no_connect line (at 12.7 -26.67 0) (length 2.54) hide
          (name "VSF8" (effects (font (size 1.27 1.27))))
          (number "D9" (effects (font (size 1.27 1.27))))
        )
        (pin no_connect line (at 8.89 1.27 0) (length 2.54) hide
          (name "RFU" (effects (font (size 1.27 1.27))))
          (number "E2" (effects (font (size 1.27 1.27))))
        )
        (pin no_connect line (at 8.89 -1.27 0) (length 2.54) hide
          (name "RFU" (effects (font (size 1.27 1.27))))
          (number "E3" (effects (font (size 1.27 1.27))))
        )
        (pin power_in line (at 20.32 -5.08 180) (length 2.54)
          (name "VDDIM" (effects (font (size 1.27 1.27))))
          (number "E4" (effects (font (size 1.27 1.27))))
        )
        (pin no_connect line (at 8.89 -3.81 0) (length 2.54) hide
          (name "RFU" (effects (font (size 1.27 1.27))))
          (number "E5" (effects (font (size 1.27 1.27))))
        )
        (pin no_connect line (at 8.89 -6.35 0) (length 2.54) hide
          (name "RFU" (effects (font (size 1.27 1.27))))
          (number "E6" (effects (font (size 1.27 1.27))))
        )
        (pin no_connect line (at 8.89 -8.89 0) (length 2.54) hide
          (name "RFU" (effects (font (size 1.27 1.27))))
          (number "E7" (effects (font (size 1.27 1.27))))
        )
        (pin no_connect line (at 8.89 -11.43 0) (length 2.54) hide
          (name "RFU" (effects (font (size 1.27 1.27))))
          (number "E8" (effects (font (size 1.27 1.27))))
        )
        (pin no_connect line (at 8.89 -13.97 0) (length 2.54) hide
          (name "RFU" (effects (font (size 1.27 1.27))))
          (number "E9" (effects (font (size 1.27 1.27))))
        )
        (pin power_in line (at 20.32 0 180) (length 2.54)
          (name "VCC" (effects (font (size 1.27 1.27))))
          (number "F2" (effects (font (size 1.27 1.27))))
        )
        (pin power_in line (at 20.32 -25.4 180) (length 2.54)
          (name "VSSQ" (effects (font (size 1.27 1.27))))
          (number "H2" (effects (font (size 1.27 1.27))))
        )
        (pin power_in line (at 20.32 -2.54 180) (length 2.54)
          (name "VCCQ" (effects (font (size 1.27 1.27))))
          (number "H3" (effects (font (size 1.27 1.27))))
        )
        (pin no_connect line (at 8.89 -16.51 0) (length 2.54) hide
          (name "RFU" (effects (font (size 1.27 1.27))))
          (number "H4" (effects (font (size 1.27 1.27))))
        )
        (pin no_connect line (at 8.89 -19.05 0) (length 2.54) hide
          (name "RFU" (effects (font (size 1.27 1.27))))
          (number "H5" (effects (font (size 1.27 1.27))))
        )
        (pin no_connect line (at 8.89 -21.59 0) (length 2.54) hide
          (name "RFU" (effects (font (size 1.27 1.27))))
          (number "H6" (effects (font (size 1.27 1.27))))
        )
        (pin no_connect line (at 8.89 -24.13 0) (length 2.54) hide
          (name "RFU" (effects (font (size 1.27 1.27))))
          (number "H7" (effects (font (size 1.27 1.27))))
        )
        (pin passive line (at 20.32 -2.54 180) (length 2.54) hide
          (name "VCCQ" (effects (font (size 1.27 1.27))))
          (number "H8" (effects (font (size 1.27 1.27))))
        )
        (pin passive line (at 20.32 -25.4 180) (length 2.54) hide
          (name "VSSQ" (effects (font (size 1.27 1.27))))
          (number "H9" (effects (font (size 1.27 1.27))))
        )
        (pin no_connect line (at 8.89 -26.67 0) (length 2.54) hide
          (name "RFU" (effects (font (size 1.27 1.27))))
          (number "J2" (effects (font (size 1.27 1.27))))
        )
        (pin no_connect line (at 10.16 1.27 0) (length 2.54) hide
          (name "RFU" (effects (font (size 1.27 1.27))))
          (number "J3" (effects (font (size 1.27 1.27))))
        )
        (pin no_connect line (at 10.16 -1.27 0) (length 2.54) hide
          (name "RFU" (effects (font (size 1.27 1.27))))
          (number "J4" (effects (font (size 1.27 1.27))))
        )
        (pin no_connect line (at 10.16 -3.81 0) (length 2.54) hide
          (name "RFU" (effects (font (size 1.27 1.27))))
          (number "J6" (effects (font (size 1.27 1.27))))
        )
        (pin no_connect line (at 10.16 -6.35 0) (length 2.54) hide
          (name "RFU" (effects (font (size 1.27 1.27))))
          (number "J7" (effects (font (size 1.27 1.27))))
        )
        (pin no_connect line (at 10.16 -8.89 0) (length 2.54) hide
          (name "RFU" (effects (font (size 1.27 1.27))))
          (number "J8" (effects (font (size 1.27 1.27))))
        )
        (pin no_connect line (at 10.16 -11.43 0) (length 2.54) hide
          (name "RFU" (effects (font (size 1.27 1.27))))
          (number "J9" (effects (font (size 1.27 1.27))))
        )
        (pin bidirectional line (at 0 -7.62 0) (length 2.54)
          (name "DAT0" (effects (font (size 1.27 1.27))))
          (number "K2" (effects (font (size 1.27 1.27))))
        )
        (pin bidirectional line (at 0 -12.7 0) (length 2.54)
          (name "DAT2" (effects (font (size 1.27 1.27))))
          (number "K3" (effects (font (size 1.27 1.27))))
        )
        (pin no_connect line (at 10.16 -13.97 0) (length 2.54) hide
          (name "RFU" (effects (font (size 1.27 1.27))))
          (number "K4" (effects (font (size 1.27 1.27))))
        )
        (pin output line (at 20.32 -12.7 180) (length 2.54)
          (name "DS" (effects (font (size 1.27 1.27))))
          (number "K5" (effects (font (size 1.27 1.27))))
        )
        (pin no_connect line (at 10.16 -16.51 0) (length 2.54) hide
          (name "RFU" (effects (font (size 1.27 1.27))))
          (number "K6" (effects (font (size 1.27 1.27))))
        )
        (pin no_connect line (at 10.16 -19.05 0) (length 2.54) hide
          (name "RFU" (effects (font (size 1.27 1.27))))
          (number "K7" (effects (font (size 1.27 1.27))))
        )
        (pin bidirectional line (at 0 -20.32 0) (length 2.54)
          (name "DAT5" (effects (font (size 1.27 1.27))))
          (number "K8" (effects (font (size 1.27 1.27))))
        )
        (pin bidirectional line (at 0 -25.4 0) (length 2.54)
          (name "DAT7" (effects (font (size 1.27 1.27))))
          (number "K9" (effects (font (size 1.27 1.27))))
        )
        (pin passive line (at 20.32 -2.54 180) (length 2.54) hide
          (name "VCCQ" (effects (font (size 1.27 1.27))))
          (number "L2" (effects (font (size 1.27 1.27))))
        )
        (pin passive line (at 20.32 -25.4 180) (length 2.54) hide
          (name "VSSQ" (effects (font (size 1.27 1.27))))
          (number "L3" (effects (font (size 1.27 1.27))))
        )
        (pin passive line (at 20.32 -2.54 180) (length 2.54) hide
          (name "VCCQ" (effects (font (size 1.27 1.27))))
          (number "L4" (effects (font (size 1.27 1.27))))
        )
        (pin no_connect line (at 10.16 -21.59 0) (length 2.54) hide
          (name "RFU" (effects (font (size 1.27 1.27))))
          (number "L5" (effects (font (size 1.27 1.27))))
        )
        (pin no_connect line (at 10.16 -24.13 0) (length 2.54) hide
          (name "RFU" (effects (font (size 1.27 1.27))))
          (number "L6" (effects (font (size 1.27 1.27))))
        )
        (pin passive line (at 20.32 -2.54 180) (length 2.54) hide
          (name "VCCQ" (effects (font (size 1.27 1.27))))
          (number "L7" (effects (font (size 1.27 1.27))))
        )
        (pin passive line (at 20.32 -25.4 180) (length 2.54) hide
          (name "VSSQ" (effects (font (size 1.27 1.27))))
          (number "L8" (effects (font (size 1.27 1.27))))
        )
        (pin passive line (at 20.32 -2.54 180) (length 2.54) hide
          (name "VCCQ" (effects (font (size 1.27 1.27))))
          (number "L9" (effects (font (size 1.27 1.27))))
        )
        (pin no_connect line (at 10.16 -26.67 0) (length 2.54) hide
          (name "RFU" (effects (font (size 1.27 1.27))))
          (number "M2" (effects (font (size 1.27 1.27))))
        )
        (pin no_connect line (at 11.43 1.27 0) (length 2.54) hide
          (name "RFU" (effects (font (size 1.27 1.27))))
          (number "M3" (effects (font (size 1.27 1.27))))
        )
        (pin passive line (at 20.32 -25.4 180) (length 2.54) hide
          (name "VSSQ" (effects (font (size 1.27 1.27))))
          (number "M4" (effects (font (size 1.27 1.27))))
        )
        (pin input line (at 0 -2.54 0) (length 2.54)
          (name "RST_N" (effects (font (size 1.27 1.27))))
          (number "M5" (effects (font (size 1.27 1.27))))
        )
        (pin no_connect line (at 11.43 -1.27 0) (length 2.54) hide
          (name "RFU" (effects (font (size 1.27 1.27))))
          (number "M6" (effects (font (size 1.27 1.27))))
        )
        (pin passive line (at 20.32 -25.4 180) (length 2.54) hide
          (name "VSSQ" (effects (font (size 1.27 1.27))))
          (number "M7" (effects (font (size 1.27 1.27))))
        )
        (pin no_connect line (at 11.43 -3.81 0) (length 2.54) hide
          (name "RFU" (effects (font (size 1.27 1.27))))
          (number "M8" (effects (font (size 1.27 1.27))))
        )
        (pin no_connect line (at 11.43 -6.35 0) (length 2.54) hide
          (name "RFU" (effects (font (size 1.27 1.27))))
          (number "M9" (effects (font (size 1.27 1.27))))
        )
        (pin bidirectional line (at 0 -10.16 0) (length 2.54)
          (name "DAT1" (effects (font (size 1.27 1.27))))
          (number "N2" (effects (font (size 1.27 1.27))))
        )
        (pin bidirectional line (at 0 -15.24 0) (length 2.54)
          (name "DAT3" (effects (font (size 1.27 1.27))))
          (number "N3" (effects (font (size 1.27 1.27))))
        )
        (pin no_connect line (at 11.43 -8.89 0) (length 2.54) hide
          (name "RFU" (effects (font (size 1.27 1.27))))
          (number "N4" (effects (font (size 1.27 1.27))))
        )
        (pin no_connect line (at 11.43 -11.43 0) (length 2.54) hide
          (name "RFU" (effects (font (size 1.27 1.27))))
          (number "N5" (effects (font (size 1.27 1.27))))
        )
        (pin no_connect line (at 11.43 -13.97 0) (length 2.54) hide
          (name "RFU" (effects (font (size 1.27 1.27))))
          (number "N6" (effects (font (size 1.27 1.27))))
        )
        (pin no_connect line (at 11.43 -16.51 0) (length 2.54) hide
          (name "RFU" (effects (font (size 1.27 1.27))))
          (number "N7" (effects (font (size 1.27 1.27))))
        )
        (pin bidirectional line (at 0 -17.78 0) (length 2.54)
          (name "DAT4" (effects (font (size 1.27 1.27))))
          (number "N8" (effects (font (size 1.27 1.27))))
        )
        (pin bidirectional line (at 0 -22.86 0) (length 2.54)
          (name "DAT6" (effects (font (size 1.27 1.27))))
          (number "N9" (effects (font (size 1.27 1.27))))
        )
        (pin passive line (at 20.32 -25.4 180) (length 2.54) hide
          (name "VSSQ" (effects (font (size 1.27 1.27))))
          (number "P2" (effects (font (size 1.27 1.27))))
        )
        (pin passive line (at 20.32 -2.54 180) (length 2.54) hide
          (name "VCCQ" (effects (font (size 1.27 1.27))))
          (number "P3" (effects (font (size 1.27 1.27))))
        )
        (pin no_connect line (at 11.43 -19.05 0) (length 2.54) hide
          (name "RFU" (effects (font (size 1.27 1.27))))
          (number "P4" (effects (font (size 1.27 1.27))))
        )
        (pin bidirectional line (at 0 -5.08 0) (length 2.54)
          (name "CMD" (effects (font (size 1.27 1.27))))
          (number "P5" (effects (font (size 1.27 1.27))))
        )
        (pin input clock (at 0 0 0) (length 2.54)
          (name "CLK" (effects (font (size 1.27 1.27))))
          (number "P6" (effects (font (size 1.27 1.27))))
        )
        (pin no_connect line (at 11.43 -21.59 0) (length 2.54) hide
          (name "RFU" (effects (font (size 1.27 1.27))))
          (number "P7" (effects (font (size 1.27 1.27))))
        )
        (pin passive line (at 20.32 -2.54 180) (length 2.54) hide
          (name "VCCQ" (effects (font (size 1.27 1.27))))
          (number "P8" (effects (font (size 1.27 1.27))))
        )
        (pin passive line (at 20.32 -25.4 180) (length 2.54) hide
          (name "VSSQ" (effects (font (size 1.27 1.27))))
          (number "P9" (effects (font (size 1.27 1.27))))
        )
        (pin no_connect line (at 7.62 -13.97 0) (length 2.54) hide
          (name "NC" (effects (font (size 1.27 1.27))))
          (number "T1" (effects (font (size 1.27 1.27))))
        )
        (pin no_connect line (at 7.62 -16.51 0) (length 2.54) hide
          (name "NC" (effects (font (size 1.27 1.27))))
          (number "T10" (effects (font (size 1.27 1.27))))
        )
        (pin no_connect line (at 7.62 -19.05 0) (length 2.54) hide
          (name "NC" (effects (font (size 1.27 1.27))))
          (number "U1" (effects (font (size 1.27 1.27))))
        )
        (pin no_connect line (at 7.62 -26.67 0) (length 2.54) hide
          (name "NC" (effects (font (size 1.27 1.27))))
          (number "U10" (effects (font (size 1.27 1.27))))
        )
        (pin no_connect line (at 7.62 -21.59 0) (length 2.54) hide
          (name "NC" (effects (font (size 1.27 1.27))))
          (number "U2" (effects (font (size 1.27 1.27))))
        )
        (pin no_connect line (at 7.62 -24.13 0) (length 2.54) hide
          (name "NC" (effects (font (size 1.27 1.27))))
          (number "U9" (effects (font (size 1.27 1.27))))
        )
      )
      (symbol "MTFC16GAPALNA-AIT_1_1"
        (pin passive line (at 20.32 0 180) (length 2.54) hide
          (name "VCC" (effects (font (size 1.27 1.27))))
          (number "F3" (effects (font (size 1.27 1.27))))
        )
        (pin passive line (at 20.32 0 180) (length 2.54) hide
          (name "VCC" (effects (font (size 1.27 1.27))))
          (number "F4" (effects (font (size 1.27 1.27))))
        )
        (pin passive line (at 20.32 0 180) (length 2.54) hide
          (name "VCC" (effects (font (size 1.27 1.27))))
          (number "F5" (effects (font (size 1.27 1.27))))
        )
        (pin passive line (at 20.32 0 180) (length 2.54) hide
          (name "VCC" (effects (font (size 1.27 1.27))))
          (number "F6" (effects (font (size 1.27 1.27))))
        )
        (pin passive line (at 20.32 0 180) (length 2.54) hide
          (name "VCC" (effects (font (size 1.27 1.27))))
          (number "F7" (effects (font (size 1.27 1.27))))
        )
        (pin passive line (at 20.32 0 180) (length 2.54) hide
          (name "VCC" (effects (font (size 1.27 1.27))))
          (number "F8" (effects (font (size 1.27 1.27))))
        )
        (pin passive line (at 20.32 0 180) (length 2.54) hide
          (name "VCC" (effects (font (size 1.27 1.27))))
          (number "F9" (effects (font (size 1.27 1.27))))
        )
        (pin power_in line (at 20.32 -22.86 180) (length 2.54)
          (name "VSS" (effects (font (size 1.27 1.27))))
          (number "G2" (effects (font (size 1.27 1.27))))
        )
        (pin passive line (at 20.32 -22.86 180) (length 2.54) hide
          (name "VSS" (effects (font (size 1.27 1.27))))
          (number "G3" (effects (font (size 1.27 1.27))))
        )
        (pin passive line (at 20.32 -22.86 180) (length 2.54) hide
          (name "VSS" (effects (font (size 1.27 1.27))))
          (number "G4" (effects (font (size 1.27 1.27))))
        )
        (pin passive line (at 20.32 -22.86 180) (length 2.54) hide
          (name "VSS" (effects (font (size 1.27 1.27))))
          (number "G5" (effects (font (size 1.27 1.27))))
        )
        (pin passive line (at 20.32 -22.86 180) (length 2.54) hide
          (name "VSS" (effects (font (size 1.27 1.27))))
          (number "G6" (effects (font (size 1.27 1.27))))
        )
        (pin passive line (at 20.32 -22.86 180) (length 2.54) hide
          (name "VSS" (effects (font (size 1.27 1.27))))
          (number "G7" (effects (font (size 1.27 1.27))))
        )
        (pin passive line (at 20.32 -22.86 180) (length 2.54) hide
          (name "VSS" (effects (font (size 1.27 1.27))))
          (number "G8" (effects (font (size 1.27 1.27))))
        )
        (pin passive line (at 20.32 -22.86 180) (length 2.54) hide
          (name "VSS" (effects (font (size 1.27 1.27))))
          (number "G9" (effects (font (size 1.27 1.27))))
        )
        (pin passive line (at 20.32 -22.86 180) (length 2.54) hide
          (name "VSS" (effects (font (size 1.27 1.27))))
          (number "J5" (effects (font (size 1.27 1.27))))
        )
      )
    )
	(symbol "antmicroMemory:W25Q32JVSSIQ" (in_bom yes) (on_board yes)
      (property "Reference" "U" (at 33.02 -3.81 0)
        (effects (font (size 1.27 1.27) (thickness 0.15)) (justify left bottom))
      )
      (property "Value" "W25Q32JVSSIQ" (at 33.02 -6.35 0)
        (effects (font (size 1.27 1.27) (thickness 0.15)) (justify left bottom) hide)
      )
      (property "Footprint" "antmicro-footprints:SOIC-8_5.3x5.3x2mm_P1.27mm" (at 33.02 -8.89 0)
        (effects (font (size 1.27 1.27) (thickness 0.15)) (justify left bottom) hide)
      )
      (property "Datasheet" "https://www.mouser.com/datasheet/2/949/w25q32jv_revg_03272018_plus-1489806.pdf" (at 33.02 -11.43 0)
        (effects (font (size 1.27 1.27) (thickness 0.15)) (justify left bottom) hide)
      )
      (property "MPN" "W25Q32JVSSIQ" (at 33.02 -13.97 0)
        (effects (font (size 1.27 1.27) (thickness 0.15)) (justify left bottom))
      )
      (property "Manufacturer" "Winbond" (at 33.02 -16.51 0)
        (effects (font (size 1.27 1.27) (thickness 0.15)) (justify left bottom) hide)
      )
      (property "Author" "Antmicro" (at 33.02 -19.05 0)
        (effects (font (size 1.27 1.27) (thickness 0.15)) (justify left bottom) hide)
      )
      (property "License" "Apache-2.0" (at 33.02 -21.59 0)
        (effects (font (size 1.27 1.27) (thickness 0.15)) (justify left bottom) hide)
      )
      (property "ki_keywords" "FLASH, SPI, MEMORY" (at 0 0 0)
        (effects (font (size 1.27 1.27)) hide)
      )
      (property "ki_description" "Flash Memory, Serial NOR, 32 Mbit, 4M x 8bit, SPI, SOIC, 8 Pins" (at 0 0 0)
        (effects (font (size 1.27 1.27)) hide)
      )
      (symbol "W25Q32JVSSIQ_1_1"
        (rectangle (start 2.54 2.54) (end 16.51 -15.24)
          (stroke (width 0.254) (type default))
          (fill (type background))
        )
        (pin input line (at 0 -12.7 0) (length 2.54)
          (name "~{CS}" (effects (font (size 1.27 1.27))))
          (number "1" (effects (font (size 1.27 1.27))))
        )
        (pin bidirectional line (at 0 -2.54 0) (length 2.54)
          (name "SO/IO1" (effects (font (size 1.27 1.27))))
          (number "2" (effects (font (size 1.27 1.27))))
        )
        (pin bidirectional line (at 0 -5.08 0) (length 2.54)
          (name "~{WP}/IO2" (effects (font (size 1.27 1.27))))
          (number "3" (effects (font (size 1.27 1.27))))
        )
        (pin power_in line (at 19.05 -12.7 180) (length 2.54)
          (name "VSS" (effects (font (size 1.27 1.27))))
          (number "4" (effects (font (size 1.27 1.27))))
        )
        (pin bidirectional line (at 0 0 0) (length 2.54)
          (name "SI/IO0" (effects (font (size 1.27 1.27))))
          (number "5" (effects (font (size 1.27 1.27))))
        )
        (pin input line (at 0 -10.16 0) (length 2.54)
          (name "SCLK" (effects (font (size 1.27 1.27))))
          (number "6" (effects (font (size 1.27 1.27))))
        )
        (pin bidirectional line (at 0 -7.62 0) (length 2.54)
          (name "~{HOLD}/IO3" (effects (font (size 1.27 1.27))))
          (number "7" (effects (font (size 1.27 1.27))))
        )
        (pin power_in line (at 19.05 0 180) (length 2.54)
          (name "VCC" (effects (font (size 1.27 1.27))))
          (number "8" (effects (font (size 1.27 1.27))))
        )
      )
    )
	(symbol "antmicroModularConnectorsJacksWithMagnetics:L834-1G1T-S7" (in_bom yes) (on_board yes)
      (property "Reference" "J" (at 33.02 -2.54 0)
        (effects (font (size 1.27 1.27) (thickness 0.15)) (justify left bottom))
      )
      (property "Value" "L834-1G1T-S7" (at 33.02 -5.08 0)
        (effects (font (size 1.27 1.27) (thickness 0.15)) (justify left bottom) hide)
      )
      (property "Footprint" "antmicro-footprints:RJ45_BEL_L834-1G1T-S7" (at 33.02 -7.62 0)
        (effects (font (size 1.27 1.27) (thickness 0.15)) (justify left bottom) hide)
      )
      (property "Datasheet" "https://www.belfuse.com/resources/drawings/magneticsolutions/dr-mag-l834-1g1t-s7.pdf" (at 33.02 -10.16 0)
        (effects (font (size 1.27 1.27) (thickness 0.15)) (justify left bottom) hide)
      )
      (property "MPN" "L834-1G1T-S7" (at 33.02 -12.7 0)
        (effects (font (size 1.27 1.27) (thickness 0.15)) (justify left bottom))
      )
      (property "Manufacturer" "Bel Fuse" (at 33.02 -15.24 0)
        (effects (font (size 1.27 1.27) (thickness 0.15)) (justify left bottom) hide)
      )
      (property "Author" "Antmicro" (at 33.02 -17.78 0)
        (effects (font (size 1.27 1.27) (thickness 0.15)) (justify left bottom) hide)
      )
      (property "License" "Apache-2.0" (at 33.02 -20.32 0)
        (effects (font (size 1.27 1.27) (thickness 0.15)) (justify left bottom) hide)
      )
      (property "ki_keywords" "HORIZONTAL, THT, FILTERED, CONNECTOR, ETHERNET" (at 0 0 0)
        (effects (font (size 1.27 1.27)) hide)
      )
      (property "ki_description" "Modular connector with magnetics" (at 0 0 0)
        (effects (font (size 1.27 1.27)) hide)
      )
      (symbol "L834-1G1T-S7_0_0"
        (pin passive line (at 0 -30.48 0) (length 2.54)
          (name "TRCT3" (effects (font (size 1.27 1.27))))
          (number "1" (effects (font (size 1.27 1.27))))
        )
        (pin passive line (at 0 -2.54 0) (length 2.54)
          (name "TRD1-" (effects (font (size 1.27 1.27))))
          (number "10" (effects (font (size 1.27 1.27))))
        )
        (pin passive line (at 0 0 0) (length 2.54)
          (name "TRD1+" (effects (font (size 1.27 1.27))))
          (number "11" (effects (font (size 1.27 1.27))))
        )
        (pin passive line (at 0 -25.4 0) (length 2.54)
          (name "TRCT1" (effects (font (size 1.27 1.27))))
          (number "12" (effects (font (size 1.27 1.27))))
        )
        (pin passive line (at 17.78 -7.62 180) (length 2.54)
          (name "~" (effects (font (size 1.27 1.27))))
          (number "13" (effects (font (size 1.27 1.27))))
        )
        (pin passive line (at 17.78 -3.81 180) (length 2.54)
          (name "~" (effects (font (size 1.27 1.27))))
          (number "14" (effects (font (size 1.27 1.27))))
        )
        (pin passive line (at 0 -15.24 0) (length 2.54)
          (name "TRD3-" (effects (font (size 1.27 1.27))))
          (number "2" (effects (font (size 1.27 1.27))))
        )
        (pin passive line (at 0 -12.7 0) (length 2.54)
          (name "TRD3+" (effects (font (size 1.27 1.27))))
          (number "3" (effects (font (size 1.27 1.27))))
        )
        (pin passive line (at 0 -6.35 0) (length 2.54)
          (name "TRD2+" (effects (font (size 1.27 1.27))))
          (number "4" (effects (font (size 1.27 1.27))))
        )
        (pin passive line (at 0 -8.89 0) (length 2.54)
          (name "TRD2-" (effects (font (size 1.27 1.27))))
          (number "5" (effects (font (size 1.27 1.27))))
        )
        (pin passive line (at 0 -27.94 0) (length 2.54)
          (name "TRCT2" (effects (font (size 1.27 1.27))))
          (number "6" (effects (font (size 1.27 1.27))))
        )
        (pin passive line (at 0 -33.02 0) (length 2.54)
          (name "TRCT4" (effects (font (size 1.27 1.27))))
          (number "7" (effects (font (size 1.27 1.27))))
        )
        (pin passive line (at 0 -19.05 0) (length 2.54)
          (name "TRD4+" (effects (font (size 1.27 1.27))))
          (number "8" (effects (font (size 1.27 1.27))))
        )
        (pin passive line (at 0 -21.59 0) (length 2.54)
          (name "TRD4-" (effects (font (size 1.27 1.27))))
          (number "9" (effects (font (size 1.27 1.27))))
        )
        (pin passive line (at 17.78 -30.48 180) (length 2.54)
          (name "SH" (effects (font (size 1.27 1.27))))
          (number "SH" (effects (font (size 1.27 1.27))))
        )
      )
      (symbol "L834-1G1T-S7_1_1"
        (polyline
          (pts
            (xy 11.938 -15.367)
            (xy 11.684 -15.621)
          )
          (stroke (width 0.254) (type default))
          (fill (type background))
        )
        (polyline
          (pts
            (xy 11.938 -14.605)
            (xy 11.684 -14.859)
          )
          (stroke (width 0.254) (type default))
          (fill (type background))
        )
        (polyline
          (pts
            (xy 12.065 -6.477)
            (xy 11.811 -6.731)
          )
          (stroke (width 0.254) (type default))
          (fill (type background))
        )
        (polyline
          (pts
            (xy 12.065 -5.715)
            (xy 11.811 -5.969)
          )
          (stroke (width 0.254) (type default))
          (fill (type background))
        )
        (polyline
          (pts
            (xy 12.192 -15.113)
            (xy 12.573 -15.113)
          )
          (stroke (width 0.254) (type default))
          (fill (type background))
        )
        (polyline
          (pts
            (xy 12.192 -14.097)
            (xy 12.573 -15.113)
          )
          (stroke (width 0.254) (type default))
          (fill (type background))
        )
        (polyline
          (pts
            (xy 12.192 -14.097)
            (xy 12.954 -14.097)
          )
          (stroke (width 0.254) (type default))
          (fill (type background))
        )
        (polyline
          (pts
            (xy 12.319 -6.223)
            (xy 12.7 -6.223)
          )
          (stroke (width 0.254) (type default))
          (fill (type background))
        )
        (polyline
          (pts
            (xy 12.319 -5.207)
            (xy 12.7 -6.223)
          )
          (stroke (width 0.254) (type default))
          (fill (type background))
        )
        (polyline
          (pts
            (xy 12.319 -5.207)
            (xy 13.081 -5.207)
          )
          (stroke (width 0.254) (type default))
          (fill (type background))
        )
        (polyline
          (pts
            (xy 12.446 -15.113)
            (xy 12.954 -15.113)
          )
          (stroke (width 0.254) (type default))
          (fill (type background))
        )
        (polyline
          (pts
            (xy 12.573 -16.51)
            (xy 12.573 -15.494)
          )
          (stroke (width 0.254) (type default))
          (fill (type background))
        )
        (polyline
          (pts
            (xy 12.573 -16.51)
            (xy 15.113 -16.51)
          )
          (stroke (width 0.254) (type default))
          (fill (type background))
        )
        (polyline
          (pts
            (xy 12.573 -15.24)
            (xy 12.573 -16.002)
          )
          (stroke (width 0.254) (type default))
          (fill (type background))
        )
        (polyline
          (pts
            (xy 12.573 -15.113)
            (xy 12.954 -14.097)
          )
          (stroke (width 0.254) (type default))
          (fill (type background))
        )
        (polyline
          (pts
            (xy 12.573 -14.097)
            (xy 12.573 -13.462)
          )
          (stroke (width 0.254) (type default))
          (fill (type background))
        )
        (polyline
          (pts
            (xy 12.573 -13.589)
            (xy 12.573 -12.7)
          )
          (stroke (width 0.254) (type default))
          (fill (type background))
        )
        (polyline
          (pts
            (xy 12.573 -12.7)
            (xy 15.113 -12.7)
          )
          (stroke (width 0.254) (type default))
          (fill (type background))
        )
        (polyline
          (pts
            (xy 12.573 -6.223)
            (xy 13.081 -6.223)
          )
          (stroke (width 0.254) (type default))
          (fill (type background))
        )
        (polyline
          (pts
            (xy 12.7 -7.62)
            (xy 12.7 -6.604)
          )
          (stroke (width 0.254) (type default))
          (fill (type background))
        )
        (polyline
          (pts
            (xy 12.7 -7.62)
            (xy 15.24 -7.62)
          )
          (stroke (width 0.254) (type default))
          (fill (type background))
        )
        (polyline
          (pts
            (xy 12.7 -6.35)
            (xy 12.7 -7.112)
          )
          (stroke (width 0.254) (type default))
          (fill (type background))
        )
        (polyline
          (pts
            (xy 12.7 -6.223)
            (xy 13.081 -5.207)
          )
          (stroke (width 0.254) (type default))
          (fill (type background))
        )
        (polyline
          (pts
            (xy 12.7 -5.207)
            (xy 12.7 -4.572)
          )
          (stroke (width 0.254) (type default))
          (fill (type background))
        )
        (polyline
          (pts
            (xy 12.7 -4.699)
            (xy 12.7 -3.81)
          )
          (stroke (width 0.254) (type default))
          (fill (type background))
        )
        (polyline
          (pts
            (xy 12.7 -3.81)
            (xy 15.24 -3.81)
          )
          (stroke (width 0.254) (type default))
          (fill (type background))
        )
        (polyline
          (pts
            (xy 11.43 -15.875)
            (xy 11.938 -15.621)
            (xy 11.684 -15.367)
            (xy 11.43 -15.875)
          )
          (stroke (width 0.254) (type default))
          (fill (type background))
        )
        (polyline
          (pts
            (xy 11.43 -15.113)
            (xy 11.938 -14.859)
            (xy 11.684 -14.605)
            (xy 11.43 -15.113)
          )
          (stroke (width 0.254) (type default))
          (fill (type background))
        )
        (polyline
          (pts
            (xy 11.557 -6.985)
            (xy 12.065 -6.731)
            (xy 11.811 -6.477)
            (xy 11.557 -6.985)
          )
          (stroke (width 0.254) (type default))
          (fill (type background))
        )
        (polyline
          (pts
            (xy 11.557 -6.223)
            (xy 12.065 -5.969)
            (xy 11.811 -5.715)
            (xy 11.557 -6.223)
          )
          (stroke (width 0.254) (type default))
          (fill (type background))
        )
        (rectangle (start 2.54 2.54) (end 15.24 -35.56)
          (stroke (width 0.254) (type default))
          (fill (type background))
        )
        (text "G" (at 13.208 -15.621 0)
          (effects (font (size 1.27 1.27) (thickness 0.15)) (justify left bottom))
        )
        (text "G" (at 13.335 -6.731 0)
          (effects (font (size 1.27 1.27) (thickness 0.15)) (justify left bottom))
        )
        (pin passive line (at 17.78 -16.51 180) (length 2.54)
          (name "~" (effects (font (size 1.27 1.27))))
          (number "15" (effects (font (size 1.27 1.27))))
        )
        (pin passive line (at 17.78 -12.7 180) (length 2.54)
          (name "~" (effects (font (size 1.27 1.27))))
          (number "16" (effects (font (size 1.27 1.27))))
        )
      )
    )
	(symbol "antmicroOscillators:Oscillator_100MHz_ECS_3225MV" (in_bom yes) (on_board yes)
      (property "Reference" "Y" (at 31.75 -3.81 0)
        (effects (font (size 1.27 1.27) (thickness 0.15)) (justify left bottom))
      )
      (property "Value" "Oscillator_100MHz_ECS_3225MV" (at 31.75 -6.35 0)
        (effects (font (size 1.27 1.27) (thickness 0.15)) (justify left bottom) hide)
      )
      (property "Footprint" "antmicro-footprints:Oscillator_SMD_ECS_3225MV_3.2x2.5x1.2mm" (at 31.75 -8.89 0)
        (effects (font (size 1.27 1.27) (thickness 0.15)) (justify left bottom) hide)
      )
      (property "Datasheet" "https://www.mouser.com/datasheet/2/122/ECS_3225MVQ-1825332.pdf" (at 31.75 -11.43 0)
        (effects (font (size 1.27 1.27) (thickness 0.15)) (justify left bottom) hide)
      )
      (property "MPN" "ECS-3225MVQ-1000CN-TR" (at 31.75 -13.97 0)
        (effects (font (size 1.27 1.27)) (justify left))
      )
      (property "Manufacturer" "ECS Inc. International" (at 31.75 -24.13 0)
        (effects (font (size 1.27 1.27)) (justify left) hide)
      )
      (property "Val" "100 MHz" (at 31.75 -21.59 0)
        (effects (font (size 1.27 1.27)) (justify left))
      )
      (property "License" "Apache-2.0" (at 31.75 -19.05 0)
        (effects (font (size 1.27 1.27)) (justify left) hide)
      )
      (property "Author" "Antmicro" (at 31.75 -16.51 0)
        (effects (font (size 1.27 1.27)) (justify left) hide)
      )
      (property "ki_keywords" "OSCILLATOR" (at 0 0 0)
        (effects (font (size 1.27 1.27)) hide)
      )
      (property "ki_description" "Oscillator, 100 MHz, CMOS, SMD, 3.2mm x 2.5mm, MultiVolt ECS-3225MVQ Series" (at 0 0 0)
        (effects (font (size 1.27 1.27)) hide)
      )
      (symbol "Oscillator_100MHz_ECS_3225MV_1_1"
        (polyline
          (pts
            (xy 7.62 -1.27)
            (xy 8.255 -1.27)
            (xy 8.255 0)
            (xy 8.89 0)
            (xy 8.89 -1.27)
            (xy 9.525 -1.27)
            (xy 9.525 0)
            (xy 10.16 0)
            (xy 10.16 -1.27)
          )
          (stroke (width 0.254) (type default))
          (fill (type background))
        )
        (rectangle (start 2.54 2.54) (end 16.51 -7.62)
          (stroke (width 0.254) (type default))
          (fill (type background))
        )
        (pin input line (at 0 -2.54 0) (length 2.54)
          (name "EN" (effects (font (size 1.27 1.27))))
          (number "1" (effects (font (size 1.27 1.27))))
        )
        (pin power_in line (at 0 -5.08 0) (length 2.54)
          (name "GND" (effects (font (size 1.27 1.27))))
          (number "2" (effects (font (size 1.27 1.27))))
        )
        (pin output line (at 19.05 0 180) (length 2.54)
          (name "OUT" (effects (font (size 1.27 1.27))))
          (number "3" (effects (font (size 1.27 1.27))))
        )
        (pin power_in line (at 0 0 0) (length 2.54)
          (name "VDD" (effects (font (size 1.27 1.27))))
          (number "4" (effects (font (size 1.27 1.27))))
        )
      )
    )
	(symbol "antmicroOscillators:Oscillator_24MHz_ASEMB" (in_bom yes) (on_board yes)
      (property "Reference" "Y" (at 17.78 -5.08 0)
        (effects (font (size 1.27 1.27) (thickness 0.15)) (justify left bottom))
      )
      (property "Value" "Oscillator_24MHz_ASEMB" (at 17.78 -15.24 0)
        (effects (font (size 1.27 1.27) (thickness 0.15)) (justify left bottom) hide)
      )
      (property "Footprint" "antmicro-footprints:Oscillator_SMD_Abracon_ASEMB_3.2x2.5mm" (at 17.78 -17.78 0)
        (effects (font (size 1.27 1.27) (thickness 0.15)) (justify left bottom) hide)
      )
      (property "Datasheet" "https://abracon.com/Oscillators/ASEMB.pdf" (at 17.78 -20.32 0)
        (effects (font (size 1.27 1.27) (thickness 0.15)) (justify left bottom) hide)
      )
      (property "MPN" "ASEMB-24.000MHZ-LC-T" (at 17.78 -7.62 0)
        (effects (font (size 1.27 1.27) (thickness 0.15)) (justify left bottom))
      )
      (property "Manufacturer" "Abracon" (at 17.78 -10.16 0)
        (effects (font (size 1.27 1.27) (thickness 0.15)) (justify left bottom) hide)
      )
      (property "Val" "24 MHz" (at 17.78 -12.7 0)
        (effects (font (size 1.27 1.27) (thickness 0.15)) (justify left bottom))
      )
      (property "Author" "Antmicro" (at 17.78 -22.86 0)
        (effects (font (size 1.27 1.27) (thickness 0.15)) (justify left bottom) hide)
      )
      (property "License" "Apache-2.0" (at 17.78 -25.4 0)
        (effects (font (size 1.27 1.27) (thickness 0.15)) (justify left bottom) hide)
      )
      (property "ki_keywords" "OSCILLATOR, MEMS" (at 0 0 0)
        (effects (font (size 1.27 1.27)) hide)
      )
      (property "ki_description" "MEMS Oscillator, Clock, Pure Silicon&trade;, 24 MHz, SMD, 3.2mm x 2.5mm, 50 ppm, 3.3 V, ASEMB, LVCMOS" (at 0 0 0)
        (effects (font (size 1.27 1.27)) hide)
      )
      (symbol "Oscillator_24MHz_ASEMB_1_1"
        (polyline
          (pts
            (xy 7.62 -1.27)
            (xy 8.255 -1.27)
            (xy 8.255 0)
            (xy 8.89 0)
            (xy 8.89 -1.27)
            (xy 9.525 -1.27)
            (xy 9.525 0)
            (xy 10.16 0)
            (xy 10.16 -1.27)
          )
          (stroke (width 0.254) (type default))
          (fill (type background))
        )
        (rectangle (start 2.54 2.54) (end 16.51 -7.62)
          (stroke (width 0.254) (type default))
          (fill (type background))
        )
        (pin input line (at 0 -2.54 0) (length 2.54)
          (name "EN" (effects (font (size 1.27 1.27))))
          (number "1" (effects (font (size 1.27 1.27))))
        )
        (pin power_in line (at 0 -5.08 0) (length 2.54)
          (name "GND" (effects (font (size 1.27 1.27))))
          (number "2" (effects (font (size 1.27 1.27))))
        )
        (pin output line (at 19.05 0 180) (length 2.54)
          (name "OUT" (effects (font (size 1.27 1.27))))
          (number "3" (effects (font (size 1.27 1.27))))
        )
        (pin power_in line (at 0 0 0) (length 2.54)
          (name "VDD" (effects (font (size 1.27 1.27))))
          (number "4" (effects (font (size 1.27 1.27))))
        )
      )
    )
	(symbol "antmicroOscillators:Oscillator_25MHz_ESC_2016MV" (in_bom yes) (on_board yes)
      (property "Reference" "Y" (at 25.4 -2.54 0)
        (effects (font (size 1.27 1.27) (thickness 0.15)) (justify left bottom))
      )
      (property "Value" "Oscillator_25MHz_ESC_2016MV" (at 25.4 -12.7 0)
        (effects (font (size 1.27 1.27) (thickness 0.15)) (justify left bottom) hide)
      )
      (property "Footprint" "antmicro-footprints:Oscillator_SMD_ECS_2016MV_2x1.6x0.85mm" (at 25.4 -15.24 0)
        (effects (font (size 1.27 1.27) (thickness 0.15)) (justify left bottom) hide)
      )
      (property "Datasheet" "https://ecsxtal.com/store/pdf/ECS-2016MV.pdf" (at 25.4 -17.78 0)
        (effects (font (size 1.27 1.27) (thickness 0.15)) (justify left bottom) hide)
      )
      (property "MPN" "ECS-2016MV-250-CN-TR" (at 25.4 -5.08 0)
        (effects (font (size 1.27 1.27) (thickness 0.15)) (justify left bottom))
      )
      (property "Manufacturer" "ECS Inc. International" (at 25.4 -7.62 0)
        (effects (font (size 1.27 1.27) (thickness 0.15)) (justify left bottom) hide)
      )
      (property "Val" "25 MHz" (at 25.4 -10.16 0)
        (effects (font (size 1.27 1.27) (thickness 0.15)) (justify left bottom))
      )
      (property "Author" "Antmicro" (at 25.4 -20.32 0)
        (effects (font (size 1.27 1.27) (thickness 0.15)) (justify left bottom) hide)
      )
      (property "License" "Apache-2.0" (at 25.4 -22.86 0)
        (effects (font (size 1.27 1.27) (thickness 0.15)) (justify left bottom) hide)
      )
      (property "ki_keywords" "OSCILLATOR" (at 0 0 0)
        (effects (font (size 1.27 1.27)) hide)
      )
      (property "ki_description" "Oscillator, 25 MHz, HCMOS, SMD, 2mm x 1.6mm, MultiVolt ECS-2016MV Series" (at 0 0 0)
        (effects (font (size 1.27 1.27)) hide)
      )
      (symbol "Oscillator_25MHz_ESC_2016MV_1_1"
        (polyline
          (pts
            (xy 7.62 -1.27)
            (xy 8.255 -1.27)
            (xy 8.255 0)
            (xy 8.89 0)
            (xy 8.89 -1.27)
            (xy 9.525 -1.27)
            (xy 9.525 0)
            (xy 10.16 0)
            (xy 10.16 -1.27)
          )
          (stroke (width 0.254) (type default))
          (fill (type background))
        )
        (rectangle (start 2.54 2.54) (end 16.51 -7.62)
          (stroke (width 0.254) (type default))
          (fill (type background))
        )
        (pin input line (at 0 -2.54 0) (length 2.54)
          (name "EN" (effects (font (size 1.27 1.27))))
          (number "1" (effects (font (size 1.27 1.27))))
        )
        (pin power_in line (at 0 -5.08 0) (length 2.54)
          (name "GND" (effects (font (size 1.27 1.27))))
          (number "2" (effects (font (size 1.27 1.27))))
        )
        (pin output line (at 19.05 0 180) (length 2.54)
          (name "OUT" (effects (font (size 1.27 1.27))))
          (number "3" (effects (font (size 1.27 1.27))))
        )
        (pin power_in line (at 0 0 0) (length 2.54)
          (name "VDD" (effects (font (size 1.27 1.27))))
          (number "4" (effects (font (size 1.27 1.27))))
        )
      )
    )
	(symbol "antmicroPMICPowerSequencers:LM3881" (in_bom yes) (on_board yes)
      (property "Reference" "U" (at 30.48 -2.54 0)
        (effects (font (size 1.27 1.27) (thickness 0.15)) (justify left bottom))
      )
      (property "Value" "LM3881" (at 30.48 -7.62 0)
        (effects (font (size 1.27 1.27) (thickness 0.15)) (justify left bottom) hide)
      )
      (property "Footprint" "antmicro-footprints:VSSOP-8_3x3mm_P0.65mm" (at 30.48 -10.16 0)
        (effects (font (size 1.27 1.27) (thickness 0.15)) (justify left bottom) hide)
      )
      (property "Datasheet" "http://www.ti.com/lit/ds/symlink/lm3881.pdf" (at 30.48 -12.7 0)
        (effects (font (size 1.27 1.27) (thickness 0.15)) (justify left bottom) hide)
      )
      (property "Manufacturer" "Texas Instruments" (at 30.48 -15.24 0)
        (effects (font (size 1.27 1.27) (thickness 0.15)) (justify left bottom) hide)
      )
      (property "MPN" "LM3881MME/NOPB" (at 30.48 -5.08 0)
        (effects (font (size 1.27 1.27) (thickness 0.15)) (justify left bottom))
      )
      (property "Author" "Antmicro" (at 30.48 -17.78 0)
        (effects (font (size 1.27 1.27) (thickness 0.15)) (justify left bottom) hide)
      )
      (property "License" "Apache-2.0" (at 30.48 -20.32 0)
        (effects (font (size 1.27 1.27) (thickness 0.15)) (justify left bottom) hide)
      )
      (property "ki_keywords" "SMT, PMIC, IC, POWER, SEQUENCER" (at 0 0 0)
        (effects (font (size 1.27 1.27)) hide)
      )
      (property "ki_description" "Power Sequencer, 3-Monitors, 2.7V-5.5Vin,VSSOP-8" (at 0 0 0)
        (effects (font (size 1.27 1.27)) hide)
      )
      (symbol "LM3881_1_1"
        (rectangle (start 2.54 2.54) (end 13.97 -10.16)
          (stroke (width 0.254) (type default))
          (fill (type background))
        )
        (pin power_in line (at 0 0 0) (length 2.54)
          (name "VCC" (effects (font (size 1.27 1.27))))
          (number "1" (effects (font (size 1.27 1.27))))
        )
        (pin passive line (at 0 -2.54 0) (length 2.54)
          (name "EN" (effects (font (size 1.27 1.27))))
          (number "2" (effects (font (size 1.27 1.27))))
        )
        (pin power_in line (at 16.51 -7.62 180) (length 2.54)
          (name "GND" (effects (font (size 1.27 1.27))))
          (number "3" (effects (font (size 1.27 1.27))))
        )
        (pin input line (at 0 -5.08 0) (length 2.54)
          (name "INV" (effects (font (size 1.27 1.27))))
          (number "4" (effects (font (size 1.27 1.27))))
        )
        (pin passive line (at 0 -7.62 0) (length 2.54)
          (name "TADJ" (effects (font (size 1.27 1.27))))
          (number "5" (effects (font (size 1.27 1.27))))
        )
        (pin open_collector line (at 16.51 -5.08 180) (length 2.54)
          (name "FLAG3" (effects (font (size 1.27 1.27))))
          (number "6" (effects (font (size 1.27 1.27))))
        )
        (pin open_collector line (at 16.51 -2.54 180) (length 2.54)
          (name "FLAG2" (effects (font (size 1.27 1.27))))
          (number "7" (effects (font (size 1.27 1.27))))
        )
        (pin open_collector line (at 16.51 0 180) (length 2.54)
          (name "FLAG1" (effects (font (size 1.27 1.27))))
          (number "8" (effects (font (size 1.27 1.27))))
        )
      )
    )
	(symbol "antmicroPMICVoltageRegulatorsDCDCSwitchingControllers:TPS51200DRCT" (in_bom yes) (on_board yes)
      (property "Reference" "U" (at 35.56 -2.54 0)
        (effects (font (size 1.27 1.27) (thickness 0.15)) (justify left bottom))
      )
      (property "Value" "TPS51200DRCT" (at 35.56 -7.62 0)
        (effects (font (size 1.27 1.27) (thickness 0.15)) (justify left bottom) hide)
      )
      (property "Footprint" "antmicro-footprints:VSON-10-1EP_3x3mm" (at 35.56 -10.16 0)
        (effects (font (size 1.27 1.27) (thickness 0.15)) (justify left bottom) hide)
      )
      (property "Datasheet" "https://www.ti.com/lit/ds/symlink/tps51200.pdf?ts=1685420125657" (at 35.56 -12.7 0)
        (effects (font (size 1.27 1.27) (thickness 0.15)) (justify left bottom) hide)
      )
      (property "MPN" "TPS51200DRCT" (at 35.56 -5.08 0)
        (effects (font (size 1.27 1.27) (thickness 0.15)) (justify left bottom))
      )
      (property "Manufacturer" "Texas Instruments" (at 35.56 -15.24 0)
        (effects (font (size 1.27 1.27) (thickness 0.15)) (justify left bottom) hide)
      )
      (property "Author" "Antmicro" (at 35.56 -20.32 0)
        (effects (font (size 1.27 1.27) (thickness 0.15)) (justify left bottom) hide)
      )
      (property "License" "Apache-2.0" (at 35.56 -22.86 0)
        (effects (font (size 1.27 1.27) (thickness 0.15)) (justify left bottom) hide)
      )
      (property "ki_keywords" "SMT, PMIC, IC" (at 0 0 0)
        (effects (font (size 1.27 1.27)) hide)
      )
      (property "ki_description" "Fixed LDO Voltage Regulator, 2.375 V to 3.5 V, 0.8 V Dropout, 1.25 V / 3 A out, VSON-10" (at 0 0 0)
        (effects (font (size 1.27 1.27)) hide)
      )
      (property "ki_fp_filters" "*VSON?10?1EP?3x3mm?P0.5mm*" (at 0 0 0)
        (effects (font (size 1.27 1.27)) hide)
      )
      (symbol "TPS51200DRCT_0_1"
        (rectangle (start 2.54 2.54) (end 17.78 -13.97)
          (stroke (width 0.254) (type default))
          (fill (type background))
        )
        (pin input line (at 0 -8.89 0) (length 2.54)
          (name "REFIN" (effects (font (size 1.27 1.27))))
          (number "1" (effects (font (size 1.27 1.27))))
        )
        (pin power_in line (at 0 0 0) (length 2.54)
          (name "VIN" (effects (font (size 1.27 1.27))))
          (number "10" (effects (font (size 1.27 1.27))))
        )
        (pin passive line (at 20.32 -11.43 180) (length 2.54) hide
          (name "GND" (effects (font (size 1.27 1.27))))
          (number "11" (effects (font (size 1.27 1.27))))
        )
        (pin power_in line (at 0 -11.43 0) (length 2.54)
          (name "VLDOIN" (effects (font (size 1.27 1.27))))
          (number "2" (effects (font (size 1.27 1.27))))
        )
        (pin power_out line (at 20.32 0 180) (length 2.54)
          (name "VO" (effects (font (size 1.27 1.27))))
          (number "3" (effects (font (size 1.27 1.27))))
        )
        (pin passive line (at 20.32 -11.43 180) (length 2.54) hide
          (name "GND" (effects (font (size 1.27 1.27))))
          (number "4" (effects (font (size 1.27 1.27))))
        )
        (pin input line (at 20.32 -2.54 180) (length 2.54)
          (name "VOSNS" (effects (font (size 1.27 1.27))))
          (number "5" (effects (font (size 1.27 1.27))))
        )
        (pin power_out line (at 20.32 -8.89 180) (length 2.54)
          (name "REFOUT" (effects (font (size 1.27 1.27))))
          (number "6" (effects (font (size 1.27 1.27))))
        )
        (pin input line (at 0 -5.08 0) (length 2.54)
          (name "EN" (effects (font (size 1.27 1.27))))
          (number "7" (effects (font (size 1.27 1.27))))
        )
        (pin power_in line (at 20.32 -11.43 180) (length 2.54)
          (name "GND" (effects (font (size 1.27 1.27))))
          (number "8" (effects (font (size 1.27 1.27))))
        )
        (pin open_collector line (at 0 -2.54 0) (length 2.54)
          (name "PGOOD" (effects (font (size 1.27 1.27))))
          (number "9" (effects (font (size 1.27 1.27))))
        )
      )
    )
	(symbol "antmicroPMICVoltageRegulatorsDCDCSwitchingRegulators:LM21212-2" (in_bom yes) (on_board yes)
      (property "Reference" "U" (at 45.72 -3.81 0)
        (effects (font (size 1.27 1.27) (thickness 0.15)) (justify left bottom))
      )
      (property "Value" "LM21212-2" (at 45.72 -11.43 0)
        (effects (font (size 1.27 1.27) (thickness 0.15)) (justify left bottom) hide)
      )
      (property "Footprint" "antmicro-footprints:HTSSOP-20_W4.4mm_P0.65mm" (at 45.72 -13.97 0)
        (effects (font (size 1.27 1.27) (thickness 0.15)) (justify left bottom) hide)
      )
      (property "Datasheet" "https://www.ti.com/product/LM21212-2" (at 45.72 -16.51 0)
        (effects (font (size 1.27 1.27) (thickness 0.15)) (justify left bottom) hide)
      )
      (property "Manufacturer" "Texas Instruments" (at 45.72 -19.05 0)
        (effects (font (size 1.27 1.27) (thickness 0.15)) (justify left bottom) hide)
      )
      (property "MPN" "LM21212MH-2/NOPB" (at 45.72 -6.35 0)
        (effects (font (size 1.27 1.27) (thickness 0.15)) (justify left bottom))
      )
      (property "Author" "Antmicro" (at 45.72 -21.59 0)
        (effects (font (size 1.27 1.27) (thickness 0.15)) (justify left bottom) hide)
      )
      (property "License" "Apache-2.0" (at 45.72 -24.13 0)
        (effects (font (size 1.27 1.27) (thickness 0.15)) (justify left bottom) hide)
      )
      (property "ki_keywords" "SMT, PMIC, IC, SWITCHING, BUCK, VOLTAGE, REGULATOR" (at 0 0 0)
        (effects (font (size 1.27 1.27)) hide)
      )
      (property "ki_description" "DC-DC Switching Buck Step Down Regulator, Adjustable, 2.95V-5.5Vin, 600mV-5.5Vout, 12Aout, HTSSOP-20" (at 0 0 0)
        (effects (font (size 1.27 1.27)) hide)
      )
      (symbol "LM21212-2_1_1"
        (rectangle (start 2.54 2.54) (end 17.78 -25.4)
          (stroke (width 0.254) (type default))
          (fill (type background))
        )
        (pin passive line (at 0 -10.16 0) (length 2.54)
          (name "FADJ" (effects (font (size 1.27 1.27))))
          (number "1" (effects (font (size 1.27 1.27))))
        )
        (pin passive line (at 0 -17.78 0) (length 2.54)
          (name "PGND" (effects (font (size 1.27 1.27))))
          (number "10" (effects (font (size 1.27 1.27))))
        )
        (pin passive line (at 20.32 0 180) (length 2.54)
          (name "SW" (effects (font (size 1.27 1.27))))
          (number "11" (effects (font (size 1.27 1.27))))
        )
        (pin passive line (at 20.32 0 180) (length 2.54) hide
          (name "SW" (effects (font (size 1.27 1.27))))
          (number "12" (effects (font (size 1.27 1.27))))
        )
        (pin passive line (at 20.32 0 180) (length 2.54) hide
          (name "SW" (effects (font (size 1.27 1.27))))
          (number "13" (effects (font (size 1.27 1.27))))
        )
        (pin passive line (at 20.32 0 180) (length 2.54) hide
          (name "SW" (effects (font (size 1.27 1.27))))
          (number "14" (effects (font (size 1.27 1.27))))
        )
        (pin passive line (at 20.32 0 180) (length 2.54) hide
          (name "SW" (effects (font (size 1.27 1.27))))
          (number "15" (effects (font (size 1.27 1.27))))
        )
        (pin passive line (at 20.32 0 180) (length 2.54) hide
          (name "SW" (effects (font (size 1.27 1.27))))
          (number "16" (effects (font (size 1.27 1.27))))
        )
        (pin passive line (at 20.32 -12.7 180) (length 2.54)
          (name "PGOOD" (effects (font (size 1.27 1.27))))
          (number "17" (effects (font (size 1.27 1.27))))
        )
        (pin passive line (at 20.32 -10.16 180) (length 2.54)
          (name "COMP" (effects (font (size 1.27 1.27))))
          (number "18" (effects (font (size 1.27 1.27))))
        )
        (pin passive line (at 20.32 -7.62 180) (length 2.54)
          (name "FB" (effects (font (size 1.27 1.27))))
          (number "19" (effects (font (size 1.27 1.27))))
        )
        (pin passive line (at 0 -12.7 0) (length 2.54)
          (name "SS" (effects (font (size 1.27 1.27))))
          (number "2" (effects (font (size 1.27 1.27))))
          (alternate "TRK" passive line)
        )
        (pin passive line (at 0 -22.86 0) (length 2.54)
          (name "AGND" (effects (font (size 1.27 1.27))))
          (number "20" (effects (font (size 1.27 1.27))))
        )
        (pin passive line (at 0 -20.32 0) (length 2.54)
          (name "EP" (effects (font (size 1.27 1.27))))
          (number "21" (effects (font (size 1.27 1.27))))
        )
        (pin passive line (at 0 -7.62 0) (length 2.54)
          (name "EN" (effects (font (size 1.27 1.27))))
          (number "3" (effects (font (size 1.27 1.27))))
        )
        (pin passive line (at 0 0 0) (length 2.54)
          (name "AVIN" (effects (font (size 1.27 1.27))))
          (number "4" (effects (font (size 1.27 1.27))))
        )
        (pin passive line (at 0 -2.54 0) (length 2.54)
          (name "PVIN" (effects (font (size 1.27 1.27))))
          (number "5" (effects (font (size 1.27 1.27))))
        )
        (pin passive line (at 0 -2.54 0) (length 2.54) hide
          (name "PVIN" (effects (font (size 1.27 1.27))))
          (number "6" (effects (font (size 1.27 1.27))))
        )
        (pin passive line (at 0 -2.54 0) (length 2.54) hide
          (name "PVIN" (effects (font (size 1.27 1.27))))
          (number "7" (effects (font (size 1.27 1.27))))
        )
        (pin passive line (at 0 -17.78 0) (length 2.54) hide
          (name "PGND" (effects (font (size 1.27 1.27))))
          (number "8" (effects (font (size 1.27 1.27))))
        )
        (pin passive line (at 0 -17.78 0) (length 2.54) hide
          (name "PGND" (effects (font (size 1.27 1.27))))
          (number "9" (effects (font (size 1.27 1.27))))
        )
      )
    )
	(symbol "antmicroPMICVoltageRegulatorsLinear:TPS54561QDPRRQ1" (in_bom yes) (on_board yes)
      (property "Reference" "U" (at 38.1 -2.54 0)
        (effects (font (size 1.27 1.27) (thickness 0.15)) (justify left bottom))
      )
      (property "Value" "TPS54561QDPRRQ1" (at 38.1 -7.62 0)
        (effects (font (size 1.27 1.27) (thickness 0.15)) (justify left bottom) hide)
      )
      (property "Footprint" "antmicro-footprints:WSON-10-1EP_4x4mm_P0.8mm_EP2.6x3mm" (at 38.1 -10.16 0)
        (effects (font (size 1.27 1.27) (thickness 0.15)) (justify left bottom) hide)
      )
      (property "Datasheet" "https://www.ti.com/lit/ds/symlink/tps54561-q1.pdf?ts=1678720110394&ref_url=https%253A%252F%252Fwww.google.com%252F" (at 38.1 -12.7 0)
        (effects (font (size 1.27 1.27) (thickness 0.15)) (justify left bottom) hide)
      )
      (property "Manufacturer" "Texas Instruments" (at 38.1 -15.24 0)
        (effects (font (size 1.27 1.27) (thickness 0.15)) (justify left bottom) hide)
      )
      (property "MPN" "TPS54561QDPRRQ1" (at 38.1 -5.08 0)
        (effects (font (size 1.27 1.27) (thickness 0.15)) (justify left bottom))
      )
      (property "Author" "Antmicro" (at 38.1 -17.78 0)
        (effects (font (size 1.27 1.27) (thickness 0.15)) (justify left bottom) hide)
      )
      (property "License" "Apache-2.0" (at 38.1 -20.32 0)
        (effects (font (size 1.27 1.27) (thickness 0.15)) (justify left bottom) hide)
      )
      (property "ki_keywords" "SMT, PMIC, IC, SWITCHING, VOLTAGE, REGULATOR, DC-DC" (at 0 0 0)
        (effects (font (size 1.27 1.27)) hide)
      )
      (property "ki_description" "DC/DC converter" (at 0 0 0)
        (effects (font (size 1.27 1.27)) hide)
      )
      (symbol "TPS54561QDPRRQ1_1_1"
        (rectangle (start 2.54 2.54) (end 22.86 -21.59)
          (stroke (width 0.254) (type default))
          (fill (type background))
        )
        (pin output line (at 25.4 -2.54 180) (length 2.54)
          (name "BOOT" (effects (font (size 1.27 1.27))))
          (number "1" (effects (font (size 1.27 1.27))))
        )
        (pin output line (at 25.4 0 180) (length 2.54)
          (name "PWRGD" (effects (font (size 1.27 1.27))))
          (number "10" (effects (font (size 1.27 1.27))))
        )
        (pin passive line (at 0 -19.05 0) (length 2.54) hide
          (name "GND" (effects (font (size 1.27 1.27))))
          (number "11" (effects (font (size 1.27 1.27))))
        )
        (pin power_in line (at 0 0 0) (length 2.54)
          (name "V_{DD}" (effects (font (size 1.27 1.27))))
          (number "2" (effects (font (size 1.27 1.27))))
        )
        (pin input line (at 0 -2.54 0) (length 2.54)
          (name "EN" (effects (font (size 1.27 1.27))))
          (number "3" (effects (font (size 1.27 1.27))))
        )
        (pin input line (at 0 -10.16 0) (length 2.54)
          (name "SS/TR" (effects (font (size 1.27 1.27))))
          (number "4" (effects (font (size 1.27 1.27))))
        )
        (pin input line (at 0 -7.62 0) (length 2.54)
          (name "RT/CLK" (effects (font (size 1.27 1.27))))
          (number "5" (effects (font (size 1.27 1.27))))
        )
        (pin input line (at 25.4 -13.97 180) (length 2.54)
          (name "FB" (effects (font (size 1.27 1.27))))
          (number "6" (effects (font (size 1.27 1.27))))
        )
        (pin output line (at 25.4 -19.05 180) (length 2.54)
          (name "COMP" (effects (font (size 1.27 1.27))))
          (number "7" (effects (font (size 1.27 1.27))))
        )
        (pin power_in line (at 0 -19.05 0) (length 2.54)
          (name "GND" (effects (font (size 1.27 1.27))))
          (number "8" (effects (font (size 1.27 1.27))))
        )
        (pin power_out line (at 25.4 -7.62 180) (length 2.54)
          (name "SW" (effects (font (size 1.27 1.27))))
          (number "9" (effects (font (size 1.27 1.27))))
        )
      )
    )
	(symbol "antmicroPciConnectors:Bus_M.2_1-2199230-6" (in_bom yes) (on_board yes)
      (property "Reference" "J" (at 45.72 -2.54 0)
        (effects (font (size 1.27 1.27) (thickness 0.15)) (justify left bottom))
      )
      (property "Value" "Bus_M.2_1-2199230-6" (at 45.72 -7.62 0)
        (effects (font (size 1.27 1.27) (thickness 0.15)) (justify left bottom) hide)
      )
      (property "Footprint" "antmicro-footprints:Bus_M.2_Socket_Key_M_TE_1-2199230-6" (at 45.72 -10.16 0)
        (effects (font (size 1.27 1.27) (thickness 0.15)) (justify left bottom) hide)
      )
      (property "Datasheet" "https://www.te.com/commerce/DocumentDelivery/DDEController?Action=srchrtrv&DocNm=2199230&DocType=Customer+Drawing&DocLang=English" (at 45.72 -12.7 0)
        (effects (font (size 1.27 1.27) (thickness 0.15)) (justify left bottom) hide)
      )
      (property "Manufacturer" "TE Connectivity" (at 45.72 -15.24 0)
        (effects (font (size 1.27 1.27) (thickness 0.15)) (justify left bottom) hide)
      )
      (property "MPN" "1-2199230-6" (at 45.72 -5.08 0)
        (effects (font (size 1.27 1.27) (thickness 0.15)) (justify left bottom))
      )
      (property "Author" "Antmicro" (at 45.72 -17.78 0)
        (effects (font (size 1.27 1.27) (thickness 0.15)) (justify left bottom) hide)
      )
      (property "License" "Apache-2.0" (at 45.72 -20.32 0)
        (effects (font (size 1.27 1.27) (thickness 0.15)) (justify left bottom) hide)
      )
      (property "ki_keywords" "HORIZONTAL, SMT, PCIE, CONNECTOR" (at 0 0 0)
        (effects (font (size 1.27 1.27)) hide)
      )
      (property "ki_description" "Key M Card Edge Connector, 0, Dual Side, 67 Contacts, Surface Mount, Right Angle, Solder" (at 0 0 0)
        (effects (font (size 1.27 1.27)) hide)
      )
      (symbol "Bus_M.2_1-2199230-6_0_0"
        (text "KEY M" (at 15.24 0 0)
          (effects (font (size 1.27 1.27) bold))
        )
      )
      (symbol "Bus_M.2_1-2199230-6_1_1"
        (rectangle (start 3.81 2.54) (end 26.67 -80.01)
          (stroke (width 0.254) (type default))
          (fill (type background))
        )
        (pin power_in line (at 30.48 -77.47 180) (length 3.81)
          (name "GND" (effects (font (size 1.27 1.27))))
          (number "1" (effects (font (size 1.27 1.27))))
        )
        (pin passive line (at 30.48 -54.61 180) (length 3.81)
          (name "LED" (effects (font (size 1.27 1.27))))
          (number "10" (effects (font (size 1.27 1.27))))
        )
        (pin input line (at 0 -69.85 0) (length 3.81)
          (name "PET3_N" (effects (font (size 1.27 1.27))))
          (number "11" (effects (font (size 1.27 1.27))))
        )
        (pin passive line (at 30.48 0 180) (length 3.81)
          (name "3V3" (effects (font (size 1.27 1.27))))
          (number "12" (effects (font (size 1.27 1.27))))
        )
        (pin input line (at 0 -67.31 0) (length 3.81)
          (name "PET3_P" (effects (font (size 1.27 1.27))))
          (number "13" (effects (font (size 1.27 1.27))))
        )
        (pin passive line (at 30.48 0 180) (length 3.81) hide
          (name "3V3" (effects (font (size 1.27 1.27))))
          (number "14" (effects (font (size 1.27 1.27))))
        )
        (pin passive line (at 30.48 -77.47 180) (length 3.81) hide
          (name "GND" (effects (font (size 1.27 1.27))))
          (number "15" (effects (font (size 1.27 1.27))))
        )
        (pin passive line (at 30.48 0 180) (length 3.81) hide
          (name "3V3" (effects (font (size 1.27 1.27))))
          (number "16" (effects (font (size 1.27 1.27))))
        )
        (pin output line (at 0 -62.23 0) (length 3.81)
          (name "PER2_N" (effects (font (size 1.27 1.27))))
          (number "17" (effects (font (size 1.27 1.27))))
        )
        (pin passive line (at 30.48 0 180) (length 3.81) hide
          (name "3V3" (effects (font (size 1.27 1.27))))
          (number "18" (effects (font (size 1.27 1.27))))
        )
        (pin output line (at 0 -59.69 0) (length 3.81)
          (name "PER2_P" (effects (font (size 1.27 1.27))))
          (number "19" (effects (font (size 1.27 1.27))))
        )
        (pin passive line (at 30.48 0 180) (length 3.81) hide
          (name "3V3" (effects (font (size 1.27 1.27))))
          (number "2" (effects (font (size 1.27 1.27))))
        )
        (pin no_connect line (at 26.67 -44.45 180) (length 3.81) hide
          (name "NC" (effects (font (size 1.27 1.27))))
          (number "20" (effects (font (size 1.27 1.27))))
        )
        (pin passive line (at 30.48 -77.47 180) (length 3.81) hide
          (name "GND" (effects (font (size 1.27 1.27))))
          (number "21" (effects (font (size 1.27 1.27))))
        )
        (pin no_connect line (at 26.67 -45.72 180) (length 3.81) hide
          (name "NC" (effects (font (size 1.27 1.27))))
          (number "22" (effects (font (size 1.27 1.27))))
        )
        (pin input line (at 0 -54.61 0) (length 3.81)
          (name "PET2_N" (effects (font (size 1.27 1.27))))
          (number "23" (effects (font (size 1.27 1.27))))
        )
        (pin no_connect line (at 26.67 -46.99 180) (length 3.81) hide
          (name "NC" (effects (font (size 1.27 1.27))))
          (number "24" (effects (font (size 1.27 1.27))))
        )
        (pin input line (at 0 -52.07 0) (length 3.81)
          (name "PET2_P" (effects (font (size 1.27 1.27))))
          (number "25" (effects (font (size 1.27 1.27))))
        )
        (pin no_connect line (at 26.67 -59.69 180) (length 3.81) hide
          (name "NC" (effects (font (size 1.27 1.27))))
          (number "26" (effects (font (size 1.27 1.27))))
        )
        (pin passive line (at 30.48 -77.47 180) (length 3.81) hide
          (name "GND" (effects (font (size 1.27 1.27))))
          (number "27" (effects (font (size 1.27 1.27))))
        )
        (pin no_connect line (at 26.67 -60.96 180) (length 3.81) hide
          (name "NC" (effects (font (size 1.27 1.27))))
          (number "28" (effects (font (size 1.27 1.27))))
        )
        (pin output line (at 0 -46.99 0) (length 3.81)
          (name "PER1_N" (effects (font (size 1.27 1.27))))
          (number "29" (effects (font (size 1.27 1.27))))
        )
        (pin passive line (at 30.48 -77.47 180) (length 3.81) hide
          (name "GND" (effects (font (size 1.27 1.27))))
          (number "3" (effects (font (size 1.27 1.27))))
        )
        (pin no_connect line (at 26.67 -62.23 180) (length 3.81) hide
          (name "NC" (effects (font (size 1.27 1.27))))
          (number "30" (effects (font (size 1.27 1.27))))
        )
        (pin output line (at 0 -44.45 0) (length 3.81)
          (name "PER1_P" (effects (font (size 1.27 1.27))))
          (number "31" (effects (font (size 1.27 1.27))))
        )
        (pin no_connect line (at 26.67 -63.5 180) (length 3.81) hide
          (name "NC" (effects (font (size 1.27 1.27))))
          (number "32" (effects (font (size 1.27 1.27))))
        )
        (pin passive line (at 30.48 -77.47 180) (length 3.81) hide
          (name "GND" (effects (font (size 1.27 1.27))))
          (number "33" (effects (font (size 1.27 1.27))))
        )
        (pin no_connect line (at 26.67 -66.04 180) (length 3.81) hide
          (name "NC" (effects (font (size 1.27 1.27))))
          (number "34" (effects (font (size 1.27 1.27))))
        )
        (pin input line (at 0 -39.37 0) (length 3.81)
          (name "PET1_N" (effects (font (size 1.27 1.27))))
          (number "35" (effects (font (size 1.27 1.27))))
        )
        (pin no_connect line (at 26.67 -67.31 180) (length 3.81) hide
          (name "NC" (effects (font (size 1.27 1.27))))
          (number "36" (effects (font (size 1.27 1.27))))
        )
        (pin input line (at 0 -36.83 0) (length 3.81)
          (name "PET1_P" (effects (font (size 1.27 1.27))))
          (number "37" (effects (font (size 1.27 1.27))))
        )
        (pin no_connect line (at 26.67 -69.85 180) (length 3.81) hide
          (name "NC" (effects (font (size 1.27 1.27))))
          (number "38" (effects (font (size 1.27 1.27))))
        )
        (pin passive line (at 30.48 -77.47 180) (length 3.81) hide
          (name "GND" (effects (font (size 1.27 1.27))))
          (number "39" (effects (font (size 1.27 1.27))))
        )
        (pin passive line (at 30.48 0 180) (length 3.81) hide
          (name "3V3" (effects (font (size 1.27 1.27))))
          (number "4" (effects (font (size 1.27 1.27))))
        )
        (pin input line (at 30.48 -31.75 180) (length 3.81)
          (name "SMB_CLK" (effects (font (size 1.27 1.27))))
          (number "40" (effects (font (size 1.27 1.27))))
        )
        (pin output line (at 0 -31.75 0) (length 3.81)
          (name "PER0_N" (effects (font (size 1.27 1.27))))
          (number "41" (effects (font (size 1.27 1.27))))
        )
        (pin bidirectional line (at 30.48 -29.21 180) (length 3.81)
          (name "SMB_DATA" (effects (font (size 1.27 1.27))))
          (number "42" (effects (font (size 1.27 1.27))))
        )
        (pin output line (at 0 -29.21 0) (length 3.81)
          (name "PER0_P" (effects (font (size 1.27 1.27))))
          (number "43" (effects (font (size 1.27 1.27))))
        )
        (pin output line (at 30.48 -26.67 180) (length 3.81)
          (name "ALERT" (effects (font (size 1.27 1.27))))
          (number "44" (effects (font (size 1.27 1.27))))
        )
        (pin passive line (at 30.48 -77.47 180) (length 3.81) hide
          (name "GND" (effects (font (size 1.27 1.27))))
          (number "45" (effects (font (size 1.27 1.27))))
        )
        (pin no_connect line (at 26.67 -68.58 180) (length 3.81) hide
          (name "NC" (effects (font (size 1.27 1.27))))
          (number "46" (effects (font (size 1.27 1.27))))
        )
        (pin input line (at 0 -24.13 0) (length 3.81)
          (name "PET0_N" (effects (font (size 1.27 1.27))))
          (number "47" (effects (font (size 1.27 1.27))))
        )
        (pin no_connect line (at 26.67 -41.91 180) (length 3.81) hide
          (name "NC" (effects (font (size 1.27 1.27))))
          (number "48" (effects (font (size 1.27 1.27))))
        )
        (pin input line (at 0 -21.59 0) (length 3.81)
          (name "PET0_P" (effects (font (size 1.27 1.27))))
          (number "49" (effects (font (size 1.27 1.27))))
        )
        (pin output line (at 0 -77.47 0) (length 3.81)
          (name "PER3_N" (effects (font (size 1.27 1.27))))
          (number "5" (effects (font (size 1.27 1.27))))
        )
        (pin input line (at 0 0 0) (length 3.81)
          (name "~{PERST}" (effects (font (size 1.27 1.27))))
          (number "50" (effects (font (size 1.27 1.27))))
        )
        (pin passive line (at 30.48 -77.47 180) (length 3.81) hide
          (name "GND" (effects (font (size 1.27 1.27))))
          (number "51" (effects (font (size 1.27 1.27))))
        )
        (pin output line (at 0 -2.54 0) (length 3.81)
          (name "~{CLKREQ}" (effects (font (size 1.27 1.27))))
          (number "52" (effects (font (size 1.27 1.27))))
        )
        (pin input line (at 0 -15.24 0) (length 3.81)
          (name "REFCLK_N" (effects (font (size 1.27 1.27))))
          (number "53" (effects (font (size 1.27 1.27))))
        )
        (pin input line (at 0 -5.08 0) (length 3.81)
          (name "~{PEWAKE}" (effects (font (size 1.27 1.27))))
          (number "54" (effects (font (size 1.27 1.27))))
        )
        (pin input line (at 0 -12.7 0) (length 3.81)
          (name "REFCLK_P" (effects (font (size 1.27 1.27))))
          (number "55" (effects (font (size 1.27 1.27))))
        )
        (pin no_connect line (at 26.67 -43.18 180) (length 3.81) hide
          (name "NC" (effects (font (size 1.27 1.27))))
          (number "56" (effects (font (size 1.27 1.27))))
        )
        (pin passive line (at 30.48 -77.47 180) (length 3.81) hide
          (name "GND" (effects (font (size 1.27 1.27))))
          (number "57" (effects (font (size 1.27 1.27))))
        )
        (pin no_connect line (at 26.67 -71.12 180) (length 3.81) hide
          (name "NC" (effects (font (size 1.27 1.27))))
          (number "58" (effects (font (size 1.27 1.27))))
        )
        (pin no_connect line (at 26.67 -39.37 180) (length 3.81) hide
          (name "NC" (effects (font (size 1.27 1.27))))
          (number "6" (effects (font (size 1.27 1.27))))
        )
        (pin no_connect line (at 26.67 -40.64 180) (length 3.81) hide
          (name "NC" (effects (font (size 1.27 1.27))))
          (number "67" (effects (font (size 1.27 1.27))))
        )
        (pin input line (at 30.48 -12.7 180) (length 3.81)
          (name "SUSCLK" (effects (font (size 1.27 1.27))))
          (number "68" (effects (font (size 1.27 1.27))))
        )
        (pin no_connect line (at 26.67 -38.1 180) (length 3.81) hide
          (name "NC" (effects (font (size 1.27 1.27))))
          (number "69" (effects (font (size 1.27 1.27))))
        )
        (pin output line (at 0 -74.93 0) (length 3.81)
          (name "PER3_P" (effects (font (size 1.27 1.27))))
          (number "7" (effects (font (size 1.27 1.27))))
        )
        (pin passive line (at 30.48 0 180) (length 3.81) hide
          (name "3V3" (effects (font (size 1.27 1.27))))
          (number "70" (effects (font (size 1.27 1.27))))
        )
        (pin passive line (at 30.48 -77.47 180) (length 3.81) hide
          (name "GND" (effects (font (size 1.27 1.27))))
          (number "71" (effects (font (size 1.27 1.27))))
        )
        (pin passive line (at 30.48 0 180) (length 3.81) hide
          (name "3V3" (effects (font (size 1.27 1.27))))
          (number "72" (effects (font (size 1.27 1.27))))
        )
        (pin passive line (at 30.48 -77.47 180) (length 3.81) hide
          (name "GND" (effects (font (size 1.27 1.27))))
          (number "73" (effects (font (size 1.27 1.27))))
        )
        (pin passive line (at 30.48 0 180) (length 3.81) hide
          (name "3V3" (effects (font (size 1.27 1.27))))
          (number "74" (effects (font (size 1.27 1.27))))
        )
        (pin passive line (at 30.48 -77.47 180) (length 3.81) hide
          (name "GND" (effects (font (size 1.27 1.27))))
          (number "75" (effects (font (size 1.27 1.27))))
        )
        (pin no_connect line (at 26.67 -64.77 180) (length 3.81) hide
          (name "NC" (effects (font (size 1.27 1.27))))
          (number "8" (effects (font (size 1.27 1.27))))
        )
        (pin passive line (at 30.48 -77.47 180) (length 3.81) hide
          (name "GND" (effects (font (size 1.27 1.27))))
          (number "9" (effects (font (size 1.27 1.27))))
        )
        (pin passive line (at 30.48 -74.93 180) (length 3.81)
          (name "MP" (effects (font (size 1.27 1.27))))
          (number "MP1" (effects (font (size 1.27 1.27))))
        )
        (pin passive line (at 30.48 -74.93 180) (length 3.81) hide
          (name "MP" (effects (font (size 1.27 1.27))))
          (number "MP2" (effects (font (size 1.27 1.27))))
        )
      )
    )
	(symbol "antmicroPciConnectors:SFF-TA-1002-4C+" (pin_names (offset 1.016)) (in_bom yes) (on_board yes)
      (property "Reference" "J" (at 46.99 0 0)
        (effects (font (size 1.27 1.27) (thickness 0.15)) (justify left bottom))
      )
      (property "Value" "SFF-TA-1002-4C+" (at 46.99 -2.54 0)
        (effects (font (size 1.27 1.27) (thickness 0.15)) (justify left bottom) hide)
      )
      (property "Footprint" "antmicro-footprints:SFF-TA-1002-4C+" (at 46.99 -5.08 0)
        (effects (font (size 1.27 1.27) (thickness 0.15)) (justify left bottom) hide)
      )
      (property "Datasheet" "https://cdn.amphenol-icc.com/media/wysiwyg/files/documentation/sme005.pdf?__cf_chl_jschl_tk__=4604d1306574a1ee474ea914090d3e0c57e266a6-1606907014-0-AbkYBTCTl__kMBcY3BDmgKpfUy32FqitwN2Lniuy8W-uyv2Ev04Q-Q5Mr7srIz_Wnur0_9chB4CRbxKSYcEh7IvAJYsUgJ0PWIS5YdRqqHg567uaZciEX2hQP4ss5l6M4XdNrxEjJppHvyRV3ku89t-VmUSzhgCb8oJlyHpTxST4dEmKZNXfM53TM0tmGirdVbCRt1Byrx5pkz_uMvNABIOj7B2-eDGK52J3DWRD76zEyjdxY7Iz11gPiOY5i_QGIR3uOwkR5LBPNXe8zGqAf8--AKa7RqDbIriQRt90_32C4zIuHqbGa05BXS135E65ov80PbVcb4eSiutCqcJUAacUwu3eVnXVeIumfihJxuP8Rv7_n6saeG_2IuQpEiskzovLGKZM3667Y-rm-AL1NRXTamtvBxqTk0vyMvZ60FgJ" (at 46.99 -7.62 0)
        (effects (font (size 1.27 1.27) (thickness 0.15)) (justify left bottom) hide)
      )
      (property "MPN" "SFF-TA-1002-4C+" (at 46.99 -10.16 0)
        (effects (font (size 1.27 1.27) (thickness 0.15)) (justify left bottom))
      )
      (property "Manufacturer" "Amphenol" (at 46.99 -12.7 0)
        (effects (font (size 1.27 1.27) (thickness 0.15)) (justify left bottom) hide)
      )
      (property "Author" "Antmicro" (at 46.99 -15.24 0)
        (effects (font (size 1.27 1.27) (thickness 0.15)) (justify left bottom) hide)
      )
      (property "License" "Apache-2.0" (at 46.99 -17.78 0)
        (effects (font (size 1.27 1.27) (thickness 0.15)) (justify left bottom) hide)
      )
      (property "ki_keywords" "CONNECTOR" (at 0 0 0)
        (effects (font (size 1.27 1.27)) hide)
      )
      (property "ki_description" "PCI connector" (at 0 0 0)
        (effects (font (size 1.27 1.27)) hide)
      )
      (symbol "SFF-TA-1002-4C+_0_0"
        (rectangle (start 5.08 2.54) (end 20.32 -228.6)
          (stroke (width 0) (type default))
          (fill (type background))
        )
        (text "KEY" (at 11.43 -154.94 0)
          (effects (font (size 1.27 1.27) (thickness 0.15)) (justify left bottom))
        )
        (text "KEY" (at 11.43 -114.3 0)
          (effects (font (size 1.27 1.27) (thickness 0.15)) (justify left bottom))
        )
        (text "KEY" (at 11.43 -38.1 0)
          (effects (font (size 1.27 1.27) (thickness 0.15)) (justify left bottom))
        )
      )
      (symbol "SFF-TA-1002-4C+_1_1"
        (rectangle (start 5.08 -152.4) (end 20.32 -154.94)
          (stroke (width 0) (type default))
          (fill (type background))
        )
        (rectangle (start 5.08 -111.76) (end 20.32 -114.3)
          (stroke (width 0) (type default))
          (fill (type background))
        )
        (rectangle (start 5.08 -35.56) (end 20.32 -38.1)
          (stroke (width 0) (type default))
          (fill (type background))
        )
        (pin passive line (at 0 -40.64 0) (length 5.08)
          (name "A1" (effects (font (size 1.27 1.27))))
          (number "A1" (effects (font (size 1.27 1.27))))
        )
        (pin passive line (at 0 -63.5 0) (length 5.08)
          (name "A10" (effects (font (size 1.27 1.27))))
          (number "A10" (effects (font (size 1.27 1.27))))
        )
        (pin passive line (at 0 -66.04 0) (length 5.08)
          (name "A11" (effects (font (size 1.27 1.27))))
          (number "A11" (effects (font (size 1.27 1.27))))
        )
        (pin passive line (at 0 -68.58 0) (length 5.08)
          (name "A12" (effects (font (size 1.27 1.27))))
          (number "A12" (effects (font (size 1.27 1.27))))
        )
        (pin passive line (at 0 -71.12 0) (length 5.08)
          (name "A13" (effects (font (size 1.27 1.27))))
          (number "A13" (effects (font (size 1.27 1.27))))
        )
        (pin passive line (at 0 -73.66 0) (length 5.08)
          (name "A14" (effects (font (size 1.27 1.27))))
          (number "A14" (effects (font (size 1.27 1.27))))
        )
        (pin passive line (at 0 -76.2 0) (length 5.08)
          (name "A15" (effects (font (size 1.27 1.27))))
          (number "A15" (effects (font (size 1.27 1.27))))
        )
        (pin passive line (at 0 -78.74 0) (length 5.08)
          (name "A16" (effects (font (size 1.27 1.27))))
          (number "A16" (effects (font (size 1.27 1.27))))
        )
        (pin passive line (at 0 -81.28 0) (length 5.08)
          (name "A17" (effects (font (size 1.27 1.27))))
          (number "A17" (effects (font (size 1.27 1.27))))
        )
        (pin passive line (at 0 -83.82 0) (length 5.08)
          (name "A18" (effects (font (size 1.27 1.27))))
          (number "A18" (effects (font (size 1.27 1.27))))
        )
        (pin passive line (at 0 -86.36 0) (length 5.08)
          (name "A19" (effects (font (size 1.27 1.27))))
          (number "A19" (effects (font (size 1.27 1.27))))
        )
        (pin passive line (at 0 -43.18 0) (length 5.08)
          (name "A2" (effects (font (size 1.27 1.27))))
          (number "A2" (effects (font (size 1.27 1.27))))
        )
        (pin passive line (at 0 -88.9 0) (length 5.08)
          (name "A20" (effects (font (size 1.27 1.27))))
          (number "A20" (effects (font (size 1.27 1.27))))
        )
        (pin passive line (at 0 -91.44 0) (length 5.08)
          (name "A21" (effects (font (size 1.27 1.27))))
          (number "A21" (effects (font (size 1.27 1.27))))
        )
        (pin passive line (at 0 -93.98 0) (length 5.08)
          (name "A22" (effects (font (size 1.27 1.27))))
          (number "A22" (effects (font (size 1.27 1.27))))
        )
        (pin passive line (at 0 -96.52 0) (length 5.08)
          (name "A23" (effects (font (size 1.27 1.27))))
          (number "A23" (effects (font (size 1.27 1.27))))
        )
        (pin passive line (at 0 -99.06 0) (length 5.08)
          (name "A24" (effects (font (size 1.27 1.27))))
          (number "A24" (effects (font (size 1.27 1.27))))
        )
        (pin passive line (at 0 -101.6 0) (length 5.08)
          (name "A25" (effects (font (size 1.27 1.27))))
          (number "A25" (effects (font (size 1.27 1.27))))
        )
        (pin passive line (at 0 -104.14 0) (length 5.08)
          (name "A26" (effects (font (size 1.27 1.27))))
          (number "A26" (effects (font (size 1.27 1.27))))
        )
        (pin passive line (at 0 -106.68 0) (length 5.08)
          (name "A27" (effects (font (size 1.27 1.27))))
          (number "A27" (effects (font (size 1.27 1.27))))
        )
        (pin passive line (at 0 -109.22 0) (length 5.08)
          (name "A28" (effects (font (size 1.27 1.27))))
          (number "A28" (effects (font (size 1.27 1.27))))
        )
        (pin passive line (at 0 -116.84 0) (length 5.08)
          (name "A29" (effects (font (size 1.27 1.27))))
          (number "A29" (effects (font (size 1.27 1.27))))
        )
        (pin passive line (at 0 -45.72 0) (length 5.08)
          (name "A3" (effects (font (size 1.27 1.27))))
          (number "A3" (effects (font (size 1.27 1.27))))
        )
        (pin passive line (at 0 -119.38 0) (length 5.08)
          (name "A30" (effects (font (size 1.27 1.27))))
          (number "A30" (effects (font (size 1.27 1.27))))
        )
        (pin passive line (at 0 -121.92 0) (length 5.08)
          (name "A31" (effects (font (size 1.27 1.27))))
          (number "A31" (effects (font (size 1.27 1.27))))
        )
        (pin passive line (at 0 -124.46 0) (length 5.08)
          (name "A32" (effects (font (size 1.27 1.27))))
          (number "A32" (effects (font (size 1.27 1.27))))
        )
        (pin passive line (at 0 -127 0) (length 5.08)
          (name "A33" (effects (font (size 1.27 1.27))))
          (number "A33" (effects (font (size 1.27 1.27))))
        )
        (pin passive line (at 0 -129.54 0) (length 5.08)
          (name "A34" (effects (font (size 1.27 1.27))))
          (number "A34" (effects (font (size 1.27 1.27))))
        )
        (pin passive line (at 0 -132.08 0) (length 5.08)
          (name "A35" (effects (font (size 1.27 1.27))))
          (number "A35" (effects (font (size 1.27 1.27))))
        )
        (pin passive line (at 0 -134.62 0) (length 5.08)
          (name "A36" (effects (font (size 1.27 1.27))))
          (number "A36" (effects (font (size 1.27 1.27))))
        )
        (pin passive line (at 0 -137.16 0) (length 5.08)
          (name "A37" (effects (font (size 1.27 1.27))))
          (number "A37" (effects (font (size 1.27 1.27))))
        )
        (pin passive line (at 0 -139.7 0) (length 5.08)
          (name "A38" (effects (font (size 1.27 1.27))))
          (number "A38" (effects (font (size 1.27 1.27))))
        )
        (pin passive line (at 0 -142.24 0) (length 5.08)
          (name "A39" (effects (font (size 1.27 1.27))))
          (number "A39" (effects (font (size 1.27 1.27))))
        )
        (pin passive line (at 0 -48.26 0) (length 5.08)
          (name "A4" (effects (font (size 1.27 1.27))))
          (number "A4" (effects (font (size 1.27 1.27))))
        )
        (pin passive line (at 0 -144.78 0) (length 5.08)
          (name "A40" (effects (font (size 1.27 1.27))))
          (number "A40" (effects (font (size 1.27 1.27))))
        )
        (pin passive line (at 0 -147.32 0) (length 5.08)
          (name "A41" (effects (font (size 1.27 1.27))))
          (number "A41" (effects (font (size 1.27 1.27))))
        )
        (pin passive line (at 0 -149.86 0) (length 5.08)
          (name "A42" (effects (font (size 1.27 1.27))))
          (number "A42" (effects (font (size 1.27 1.27))))
        )
        (pin passive line (at 0 -157.48 0) (length 5.08)
          (name "A43" (effects (font (size 1.27 1.27))))
          (number "A43" (effects (font (size 1.27 1.27))))
        )
        (pin passive line (at 0 -160.02 0) (length 5.08)
          (name "A44" (effects (font (size 1.27 1.27))))
          (number "A44" (effects (font (size 1.27 1.27))))
        )
        (pin passive line (at 0 -162.56 0) (length 5.08)
          (name "A45" (effects (font (size 1.27 1.27))))
          (number "A45" (effects (font (size 1.27 1.27))))
        )
        (pin passive line (at 0 -165.1 0) (length 5.08)
          (name "A46" (effects (font (size 1.27 1.27))))
          (number "A46" (effects (font (size 1.27 1.27))))
        )
        (pin passive line (at 0 -167.64 0) (length 5.08)
          (name "A47" (effects (font (size 1.27 1.27))))
          (number "A47" (effects (font (size 1.27 1.27))))
        )
        (pin passive line (at 0 -170.18 0) (length 5.08)
          (name "A48" (effects (font (size 1.27 1.27))))
          (number "A48" (effects (font (size 1.27 1.27))))
        )
        (pin passive line (at 0 -172.72 0) (length 5.08)
          (name "A49" (effects (font (size 1.27 1.27))))
          (number "A49" (effects (font (size 1.27 1.27))))
        )
        (pin passive line (at 0 -50.8 0) (length 5.08)
          (name "A5" (effects (font (size 1.27 1.27))))
          (number "A5" (effects (font (size 1.27 1.27))))
        )
        (pin passive line (at 0 -175.26 0) (length 5.08)
          (name "A50" (effects (font (size 1.27 1.27))))
          (number "A50" (effects (font (size 1.27 1.27))))
        )
        (pin passive line (at 0 -177.8 0) (length 5.08)
          (name "A51" (effects (font (size 1.27 1.27))))
          (number "A51" (effects (font (size 1.27 1.27))))
        )
        (pin passive line (at 0 -180.34 0) (length 5.08)
          (name "A52" (effects (font (size 1.27 1.27))))
          (number "A52" (effects (font (size 1.27 1.27))))
        )
        (pin passive line (at 0 -182.88 0) (length 5.08)
          (name "A53" (effects (font (size 1.27 1.27))))
          (number "A53" (effects (font (size 1.27 1.27))))
        )
        (pin passive line (at 0 -185.42 0) (length 5.08)
          (name "A54" (effects (font (size 1.27 1.27))))
          (number "A54" (effects (font (size 1.27 1.27))))
        )
        (pin passive line (at 0 -187.96 0) (length 5.08)
          (name "A55" (effects (font (size 1.27 1.27))))
          (number "A55" (effects (font (size 1.27 1.27))))
        )
        (pin passive line (at 0 -190.5 0) (length 5.08)
          (name "A56" (effects (font (size 1.27 1.27))))
          (number "A56" (effects (font (size 1.27 1.27))))
        )
        (pin passive line (at 0 -193.04 0) (length 5.08)
          (name "A57" (effects (font (size 1.27 1.27))))
          (number "A57" (effects (font (size 1.27 1.27))))
        )
        (pin passive line (at 0 -195.58 0) (length 5.08)
          (name "A58" (effects (font (size 1.27 1.27))))
          (number "A58" (effects (font (size 1.27 1.27))))
        )
        (pin passive line (at 0 -198.12 0) (length 5.08)
          (name "A59" (effects (font (size 1.27 1.27))))
          (number "A59" (effects (font (size 1.27 1.27))))
        )
        (pin passive line (at 0 -53.34 0) (length 5.08)
          (name "A6" (effects (font (size 1.27 1.27))))
          (number "A6" (effects (font (size 1.27 1.27))))
        )
        (pin passive line (at 0 -200.66 0) (length 5.08)
          (name "A60" (effects (font (size 1.27 1.27))))
          (number "A60" (effects (font (size 1.27 1.27))))
        )
        (pin passive line (at 0 -203.2 0) (length 5.08)
          (name "A61" (effects (font (size 1.27 1.27))))
          (number "A61" (effects (font (size 1.27 1.27))))
        )
        (pin passive line (at 0 -205.74 0) (length 5.08)
          (name "A62" (effects (font (size 1.27 1.27))))
          (number "A62" (effects (font (size 1.27 1.27))))
        )
        (pin passive line (at 0 -208.28 0) (length 5.08)
          (name "A63" (effects (font (size 1.27 1.27))))
          (number "A63" (effects (font (size 1.27 1.27))))
        )
        (pin passive line (at 0 -210.82 0) (length 5.08)
          (name "A64" (effects (font (size 1.27 1.27))))
          (number "A64" (effects (font (size 1.27 1.27))))
        )
        (pin passive line (at 0 -213.36 0) (length 5.08)
          (name "A65" (effects (font (size 1.27 1.27))))
          (number "A65" (effects (font (size 1.27 1.27))))
        )
        (pin passive line (at 0 -215.9 0) (length 5.08)
          (name "A66" (effects (font (size 1.27 1.27))))
          (number "A66" (effects (font (size 1.27 1.27))))
        )
        (pin passive line (at 0 -218.44 0) (length 5.08)
          (name "A67" (effects (font (size 1.27 1.27))))
          (number "A67" (effects (font (size 1.27 1.27))))
        )
        (pin passive line (at 0 -220.98 0) (length 5.08)
          (name "A68" (effects (font (size 1.27 1.27))))
          (number "A68" (effects (font (size 1.27 1.27))))
        )
        (pin passive line (at 0 -223.52 0) (length 5.08)
          (name "A69" (effects (font (size 1.27 1.27))))
          (number "A69" (effects (font (size 1.27 1.27))))
        )
        (pin passive line (at 0 -55.88 0) (length 5.08)
          (name "A7" (effects (font (size 1.27 1.27))))
          (number "A7" (effects (font (size 1.27 1.27))))
        )
        (pin passive line (at 0 -226.06 0) (length 5.08)
          (name "A70" (effects (font (size 1.27 1.27))))
          (number "A70" (effects (font (size 1.27 1.27))))
        )
        (pin passive line (at 0 -58.42 0) (length 5.08)
          (name "A8" (effects (font (size 1.27 1.27))))
          (number "A8" (effects (font (size 1.27 1.27))))
        )
        (pin passive line (at 0 -60.96 0) (length 5.08)
          (name "A9" (effects (font (size 1.27 1.27))))
          (number "A9" (effects (font (size 1.27 1.27))))
        )
        (pin passive line (at 25.4 -40.64 180) (length 5.08)
          (name "B1" (effects (font (size 1.27 1.27))))
          (number "B1" (effects (font (size 1.27 1.27))))
        )
        (pin passive line (at 25.4 -63.5 180) (length 5.08)
          (name "B10" (effects (font (size 1.27 1.27))))
          (number "B10" (effects (font (size 1.27 1.27))))
        )
        (pin passive line (at 25.4 -66.04 180) (length 5.08)
          (name "B11" (effects (font (size 1.27 1.27))))
          (number "B11" (effects (font (size 1.27 1.27))))
        )
        (pin passive line (at 25.4 -68.58 180) (length 5.08)
          (name "B12" (effects (font (size 1.27 1.27))))
          (number "B12" (effects (font (size 1.27 1.27))))
        )
        (pin passive line (at 25.4 -71.12 180) (length 5.08)
          (name "B13" (effects (font (size 1.27 1.27))))
          (number "B13" (effects (font (size 1.27 1.27))))
        )
        (pin passive line (at 25.4 -73.66 180) (length 5.08)
          (name "B14" (effects (font (size 1.27 1.27))))
          (number "B14" (effects (font (size 1.27 1.27))))
        )
        (pin passive line (at 25.4 -76.2 180) (length 5.08)
          (name "B15" (effects (font (size 1.27 1.27))))
          (number "B15" (effects (font (size 1.27 1.27))))
        )
        (pin passive line (at 25.4 -78.74 180) (length 5.08)
          (name "B16" (effects (font (size 1.27 1.27))))
          (number "B16" (effects (font (size 1.27 1.27))))
        )
        (pin passive line (at 25.4 -81.28 180) (length 5.08)
          (name "B17" (effects (font (size 1.27 1.27))))
          (number "B17" (effects (font (size 1.27 1.27))))
        )
        (pin passive line (at 25.4 -83.82 180) (length 5.08)
          (name "B18" (effects (font (size 1.27 1.27))))
          (number "B18" (effects (font (size 1.27 1.27))))
        )
        (pin passive line (at 25.4 -86.36 180) (length 5.08)
          (name "B19" (effects (font (size 1.27 1.27))))
          (number "B19" (effects (font (size 1.27 1.27))))
        )
        (pin passive line (at 25.4 -43.18 180) (length 5.08)
          (name "B2" (effects (font (size 1.27 1.27))))
          (number "B2" (effects (font (size 1.27 1.27))))
        )
        (pin passive line (at 25.4 -88.9 180) (length 5.08)
          (name "B20" (effects (font (size 1.27 1.27))))
          (number "B20" (effects (font (size 1.27 1.27))))
        )
        (pin passive line (at 25.4 -91.44 180) (length 5.08)
          (name "B21" (effects (font (size 1.27 1.27))))
          (number "B21" (effects (font (size 1.27 1.27))))
        )
        (pin passive line (at 25.4 -93.98 180) (length 5.08)
          (name "B22" (effects (font (size 1.27 1.27))))
          (number "B22" (effects (font (size 1.27 1.27))))
        )
        (pin passive line (at 25.4 -96.52 180) (length 5.08)
          (name "B23" (effects (font (size 1.27 1.27))))
          (number "B23" (effects (font (size 1.27 1.27))))
        )
        (pin passive line (at 25.4 -99.06 180) (length 5.08)
          (name "B24" (effects (font (size 1.27 1.27))))
          (number "B24" (effects (font (size 1.27 1.27))))
        )
        (pin passive line (at 25.4 -101.6 180) (length 5.08)
          (name "B25" (effects (font (size 1.27 1.27))))
          (number "B25" (effects (font (size 1.27 1.27))))
        )
        (pin passive line (at 25.4 -104.14 180) (length 5.08)
          (name "B26" (effects (font (size 1.27 1.27))))
          (number "B26" (effects (font (size 1.27 1.27))))
        )
        (pin passive line (at 25.4 -106.68 180) (length 5.08)
          (name "B27" (effects (font (size 1.27 1.27))))
          (number "B27" (effects (font (size 1.27 1.27))))
        )
        (pin passive line (at 25.4 -109.22 180) (length 5.08)
          (name "B28" (effects (font (size 1.27 1.27))))
          (number "B28" (effects (font (size 1.27 1.27))))
        )
        (pin passive line (at 25.4 -116.84 180) (length 5.08)
          (name "B29" (effects (font (size 1.27 1.27))))
          (number "B29" (effects (font (size 1.27 1.27))))
        )
        (pin passive line (at 25.4 -45.72 180) (length 5.08)
          (name "B3" (effects (font (size 1.27 1.27))))
          (number "B3" (effects (font (size 1.27 1.27))))
        )
        (pin passive line (at 25.4 -119.38 180) (length 5.08)
          (name "B30" (effects (font (size 1.27 1.27))))
          (number "B30" (effects (font (size 1.27 1.27))))
        )
        (pin passive line (at 25.4 -121.92 180) (length 5.08)
          (name "B31" (effects (font (size 1.27 1.27))))
          (number "B31" (effects (font (size 1.27 1.27))))
        )
        (pin passive line (at 25.4 -124.46 180) (length 5.08)
          (name "B32" (effects (font (size 1.27 1.27))))
          (number "B32" (effects (font (size 1.27 1.27))))
        )
        (pin passive line (at 25.4 -127 180) (length 5.08)
          (name "B33" (effects (font (size 1.27 1.27))))
          (number "B33" (effects (font (size 1.27 1.27))))
        )
        (pin passive line (at 25.4 -129.54 180) (length 5.08)
          (name "B34" (effects (font (size 1.27 1.27))))
          (number "B34" (effects (font (size 1.27 1.27))))
        )
        (pin passive line (at 25.4 -132.08 180) (length 5.08)
          (name "B35" (effects (font (size 1.27 1.27))))
          (number "B35" (effects (font (size 1.27 1.27))))
        )
        (pin passive line (at 25.4 -134.62 180) (length 5.08)
          (name "B36" (effects (font (size 1.27 1.27))))
          (number "B36" (effects (font (size 1.27 1.27))))
        )
        (pin passive line (at 25.4 -137.16 180) (length 5.08)
          (name "B37" (effects (font (size 1.27 1.27))))
          (number "B37" (effects (font (size 1.27 1.27))))
        )
        (pin passive line (at 25.4 -139.7 180) (length 5.08)
          (name "B38" (effects (font (size 1.27 1.27))))
          (number "B38" (effects (font (size 1.27 1.27))))
        )
        (pin passive line (at 25.4 -142.24 180) (length 5.08)
          (name "B39" (effects (font (size 1.27 1.27))))
          (number "B39" (effects (font (size 1.27 1.27))))
        )
        (pin passive line (at 25.4 -48.26 180) (length 5.08)
          (name "B4" (effects (font (size 1.27 1.27))))
          (number "B4" (effects (font (size 1.27 1.27))))
        )
        (pin passive line (at 25.4 -144.78 180) (length 5.08)
          (name "B40" (effects (font (size 1.27 1.27))))
          (number "B40" (effects (font (size 1.27 1.27))))
        )
        (pin passive line (at 25.4 -147.32 180) (length 5.08)
          (name "B41" (effects (font (size 1.27 1.27))))
          (number "B41" (effects (font (size 1.27 1.27))))
        )
        (pin passive line (at 25.4 -149.86 180) (length 5.08)
          (name "B42" (effects (font (size 1.27 1.27))))
          (number "B42" (effects (font (size 1.27 1.27))))
        )
        (pin passive line (at 25.4 -157.48 180) (length 5.08)
          (name "B43" (effects (font (size 1.27 1.27))))
          (number "B43" (effects (font (size 1.27 1.27))))
        )
        (pin passive line (at 25.4 -160.02 180) (length 5.08)
          (name "B44" (effects (font (size 1.27 1.27))))
          (number "B44" (effects (font (size 1.27 1.27))))
        )
        (pin passive line (at 25.4 -162.56 180) (length 5.08)
          (name "B45" (effects (font (size 1.27 1.27))))
          (number "B45" (effects (font (size 1.27 1.27))))
        )
        (pin passive line (at 25.4 -165.1 180) (length 5.08)
          (name "B46" (effects (font (size 1.27 1.27))))
          (number "B46" (effects (font (size 1.27 1.27))))
        )
        (pin passive line (at 25.4 -167.64 180) (length 5.08)
          (name "B47" (effects (font (size 1.27 1.27))))
          (number "B47" (effects (font (size 1.27 1.27))))
        )
        (pin passive line (at 25.4 -170.18 180) (length 5.08)
          (name "B48" (effects (font (size 1.27 1.27))))
          (number "B48" (effects (font (size 1.27 1.27))))
        )
        (pin passive line (at 25.4 -172.72 180) (length 5.08)
          (name "B49" (effects (font (size 1.27 1.27))))
          (number "B49" (effects (font (size 1.27 1.27))))
        )
        (pin passive line (at 25.4 -50.8 180) (length 5.08)
          (name "B5" (effects (font (size 1.27 1.27))))
          (number "B5" (effects (font (size 1.27 1.27))))
        )
        (pin passive line (at 25.4 -175.26 180) (length 5.08)
          (name "B50" (effects (font (size 1.27 1.27))))
          (number "B50" (effects (font (size 1.27 1.27))))
        )
        (pin passive line (at 25.4 -177.8 180) (length 5.08)
          (name "B51" (effects (font (size 1.27 1.27))))
          (number "B51" (effects (font (size 1.27 1.27))))
        )
        (pin passive line (at 25.4 -180.34 180) (length 5.08)
          (name "B52" (effects (font (size 1.27 1.27))))
          (number "B52" (effects (font (size 1.27 1.27))))
        )
        (pin passive line (at 25.4 -182.88 180) (length 5.08)
          (name "B53" (effects (font (size 1.27 1.27))))
          (number "B53" (effects (font (size 1.27 1.27))))
        )
        (pin passive line (at 25.4 -185.42 180) (length 5.08)
          (name "B54" (effects (font (size 1.27 1.27))))
          (number "B54" (effects (font (size 1.27 1.27))))
        )
        (pin passive line (at 25.4 -187.96 180) (length 5.08)
          (name "B55" (effects (font (size 1.27 1.27))))
          (number "B55" (effects (font (size 1.27 1.27))))
        )
        (pin passive line (at 25.4 -190.5 180) (length 5.08)
          (name "B56" (effects (font (size 1.27 1.27))))
          (number "B56" (effects (font (size 1.27 1.27))))
        )
        (pin passive line (at 25.4 -193.04 180) (length 5.08)
          (name "B57" (effects (font (size 1.27 1.27))))
          (number "B57" (effects (font (size 1.27 1.27))))
        )
        (pin passive line (at 25.4 -195.58 180) (length 5.08)
          (name "B58" (effects (font (size 1.27 1.27))))
          (number "B58" (effects (font (size 1.27 1.27))))
        )
        (pin passive line (at 25.4 -198.12 180) (length 5.08)
          (name "B59" (effects (font (size 1.27 1.27))))
          (number "B59" (effects (font (size 1.27 1.27))))
        )
        (pin passive line (at 25.4 -53.34 180) (length 5.08)
          (name "B6" (effects (font (size 1.27 1.27))))
          (number "B6" (effects (font (size 1.27 1.27))))
        )
        (pin passive line (at 25.4 -200.66 180) (length 5.08)
          (name "B60" (effects (font (size 1.27 1.27))))
          (number "B60" (effects (font (size 1.27 1.27))))
        )
        (pin passive line (at 25.4 -203.2 180) (length 5.08)
          (name "B61" (effects (font (size 1.27 1.27))))
          (number "B61" (effects (font (size 1.27 1.27))))
        )
        (pin passive line (at 25.4 -205.74 180) (length 5.08)
          (name "B62" (effects (font (size 1.27 1.27))))
          (number "B62" (effects (font (size 1.27 1.27))))
        )
        (pin passive line (at 25.4 -208.28 180) (length 5.08)
          (name "B63" (effects (font (size 1.27 1.27))))
          (number "B63" (effects (font (size 1.27 1.27))))
        )
        (pin passive line (at 25.4 -210.82 180) (length 5.08)
          (name "B64" (effects (font (size 1.27 1.27))))
          (number "B64" (effects (font (size 1.27 1.27))))
        )
        (pin passive line (at 25.4 -213.36 180) (length 5.08)
          (name "B65" (effects (font (size 1.27 1.27))))
          (number "B65" (effects (font (size 1.27 1.27))))
        )
        (pin passive line (at 25.4 -215.9 180) (length 5.08)
          (name "B66" (effects (font (size 1.27 1.27))))
          (number "B66" (effects (font (size 1.27 1.27))))
        )
        (pin passive line (at 25.4 -218.44 180) (length 5.08)
          (name "B67" (effects (font (size 1.27 1.27))))
          (number "B67" (effects (font (size 1.27 1.27))))
        )
        (pin passive line (at 25.4 -220.98 180) (length 5.08)
          (name "B68" (effects (font (size 1.27 1.27))))
          (number "B68" (effects (font (size 1.27 1.27))))
        )
        (pin passive line (at 25.4 -223.52 180) (length 5.08)
          (name "B69" (effects (font (size 1.27 1.27))))
          (number "B69" (effects (font (size 1.27 1.27))))
        )
        (pin passive line (at 25.4 -55.88 180) (length 5.08)
          (name "B7" (effects (font (size 1.27 1.27))))
          (number "B7" (effects (font (size 1.27 1.27))))
        )
        (pin passive line (at 25.4 -226.06 180) (length 5.08)
          (name "B70" (effects (font (size 1.27 1.27))))
          (number "B70" (effects (font (size 1.27 1.27))))
        )
        (pin passive line (at 25.4 -58.42 180) (length 5.08)
          (name "B8" (effects (font (size 1.27 1.27))))
          (number "B8" (effects (font (size 1.27 1.27))))
        )
        (pin passive line (at 25.4 -60.96 180) (length 5.08)
          (name "B9" (effects (font (size 1.27 1.27))))
          (number "B9" (effects (font (size 1.27 1.27))))
        )
        (pin passive line (at 0 0 0) (length 5.08)
          (name "OA1" (effects (font (size 1.27 1.27))))
          (number "OA1" (effects (font (size 1.27 1.27))))
        )
        (pin passive line (at 0 -22.86 0) (length 5.08)
          (name "OA10" (effects (font (size 1.27 1.27))))
          (number "OA10" (effects (font (size 1.27 1.27))))
        )
        (pin passive line (at 0 -25.4 0) (length 5.08)
          (name "OA11" (effects (font (size 1.27 1.27))))
          (number "OA11" (effects (font (size 1.27 1.27))))
        )
        (pin passive line (at 0 -27.94 0) (length 5.08)
          (name "OA12" (effects (font (size 1.27 1.27))))
          (number "OA12" (effects (font (size 1.27 1.27))))
        )
        (pin passive line (at 0 -30.48 0) (length 5.08)
          (name "OA13" (effects (font (size 1.27 1.27))))
          (number "OA13" (effects (font (size 1.27 1.27))))
        )
        (pin passive line (at 0 -33.02 0) (length 5.08)
          (name "OA14" (effects (font (size 1.27 1.27))))
          (number "OA14" (effects (font (size 1.27 1.27))))
        )
        (pin passive line (at 0 -2.54 0) (length 5.08)
          (name "OA2" (effects (font (size 1.27 1.27))))
          (number "OA2" (effects (font (size 1.27 1.27))))
        )
        (pin passive line (at 0 -5.08 0) (length 5.08)
          (name "OA3" (effects (font (size 1.27 1.27))))
          (number "OA3" (effects (font (size 1.27 1.27))))
        )
        (pin passive line (at 0 -7.62 0) (length 5.08)
          (name "OA4" (effects (font (size 1.27 1.27))))
          (number "OA4" (effects (font (size 1.27 1.27))))
        )
        (pin passive line (at 0 -10.16 0) (length 5.08)
          (name "OA5" (effects (font (size 1.27 1.27))))
          (number "OA5" (effects (font (size 1.27 1.27))))
        )
        (pin passive line (at 0 -12.7 0) (length 5.08)
          (name "OA6" (effects (font (size 1.27 1.27))))
          (number "OA6" (effects (font (size 1.27 1.27))))
        )
        (pin passive line (at 0 -15.24 0) (length 5.08)
          (name "OA7" (effects (font (size 1.27 1.27))))
          (number "OA7" (effects (font (size 1.27 1.27))))
        )
        (pin passive line (at 0 -17.78 0) (length 5.08)
          (name "OA8" (effects (font (size 1.27 1.27))))
          (number "OA8" (effects (font (size 1.27 1.27))))
        )
        (pin passive line (at 0 -20.32 0) (length 5.08)
          (name "OA9" (effects (font (size 1.27 1.27))))
          (number "OA9" (effects (font (size 1.27 1.27))))
        )
        (pin passive line (at 25.4 0 180) (length 5.08)
          (name "OB1" (effects (font (size 1.27 1.27))))
          (number "OB1" (effects (font (size 1.27 1.27))))
        )
        (pin passive line (at 25.4 -22.86 180) (length 5.08)
          (name "OB10" (effects (font (size 1.27 1.27))))
          (number "OB10" (effects (font (size 1.27 1.27))))
        )
        (pin passive line (at 25.4 -25.4 180) (length 5.08)
          (name "OB11" (effects (font (size 1.27 1.27))))
          (number "OB11" (effects (font (size 1.27 1.27))))
        )
        (pin passive line (at 25.4 -27.94 180) (length 5.08)
          (name "OB12" (effects (font (size 1.27 1.27))))
          (number "OB12" (effects (font (size 1.27 1.27))))
        )
        (pin passive line (at 25.4 -30.48 180) (length 5.08)
          (name "OB13" (effects (font (size 1.27 1.27))))
          (number "OB13" (effects (font (size 1.27 1.27))))
        )
        (pin passive line (at 25.4 -33.02 180) (length 5.08)
          (name "OB14" (effects (font (size 1.27 1.27))))
          (number "OB14" (effects (font (size 1.27 1.27))))
        )
        (pin passive line (at 25.4 -2.54 180) (length 5.08)
          (name "OB2" (effects (font (size 1.27 1.27))))
          (number "OB2" (effects (font (size 1.27 1.27))))
        )
        (pin passive line (at 25.4 -5.08 180) (length 5.08)
          (name "OB3" (effects (font (size 1.27 1.27))))
          (number "OB3" (effects (font (size 1.27 1.27))))
        )
        (pin passive line (at 25.4 -7.62 180) (length 5.08)
          (name "OB4" (effects (font (size 1.27 1.27))))
          (number "OB4" (effects (font (size 1.27 1.27))))
        )
        (pin passive line (at 25.4 -10.16 180) (length 5.08)
          (name "OB5" (effects (font (size 1.27 1.27))))
          (number "OB5" (effects (font (size 1.27 1.27))))
        )
        (pin passive line (at 25.4 -12.7 180) (length 5.08)
          (name "OB6" (effects (font (size 1.27 1.27))))
          (number "OB6" (effects (font (size 1.27 1.27))))
        )
        (pin passive line (at 25.4 -15.24 180) (length 5.08)
          (name "OB7" (effects (font (size 1.27 1.27))))
          (number "OB7" (effects (font (size 1.27 1.27))))
        )
        (pin passive line (at 25.4 -17.78 180) (length 5.08)
          (name "OB8" (effects (font (size 1.27 1.27))))
          (number "OB8" (effects (font (size 1.27 1.27))))
        )
        (pin passive line (at 25.4 -20.32 180) (length 5.08)
          (name "OB9" (effects (font (size 1.27 1.27))))
          (number "OB9" (effects (font (size 1.27 1.27))))
        )
      )
    )
	(symbol "antmicroResistorNetworksArrays:8x51R_0602_array" (pin_names hide) (in_bom yes) (on_board yes)
      (property "Reference" "R" (at 26.67 -5.08 0)
        (effects (font (size 1.27 1.27) (thickness 0.15)) (justify left bottom))
      )
      (property "Value" "8x51R_0602_array" (at 26.67 -7.62 0)
        (effects (font (size 1.27 1.27) (thickness 0.15)) (justify left bottom) hide)
      )
      (property "Footprint" "antmicro-footprints:R_Array_8x0602_Panasonic_EXB2HV" (at 26.67 -12.7 0)
        (effects (font (size 1.27 1.27) (thickness 0.15)) (justify left bottom) hide)
      )
      (property "Datasheet" "http://industrial.panasonic.com/cdbs/www-data/pdf/AOC0000/AOC0000C14.pdf" (at 26.67 -15.24 0)
        (effects (font (size 1.27 1.27) (thickness 0.15)) (justify left bottom) hide)
      )
      (property "MPN" "EXB2HV510JV" (at 26.67 -17.78 0)
        (effects (font (size 1.27 1.27) (thickness 0.15)) (justify left bottom) hide)
      )
      (property "Manufacturer" "Panasonic" (at 26.67 -20.32 0)
        (effects (font (size 1.27 1.27) (thickness 0.15)) (justify left bottom) hide)
      )
      (property "Author" "Antmicro" (at 26.67 -22.86 0)
        (effects (font (size 1.27 1.27) (thickness 0.15)) (justify left bottom) hide)
      )
      (property "License" "Apache-2.0" (at 26.67 -25.4 0)
        (effects (font (size 1.27 1.27) (thickness 0.15)) (justify left bottom) hide)
      )
      (property "Val" "8x51R_0602" (at 26.67 -10.16 0)
        (effects (font (size 1.27 1.27)) (justify left bottom))
      )
      (property "ki_keywords" "SMT, RESISTOR, PASSIVE, ARRAY" (at 0 0 0)
        (effects (font (size 1.27 1.27)) hide)
      )
      (property "ki_description" "Fixed Network Resistor, 51 ohm, Isolated, 8 Resistors, 1506 [3816 Metric], Convex, ± 5%" (at 0 0 0)
        (effects (font (size 1.27 1.27)) hide)
      )
      (symbol "8x51R_0602_array_0_1"
        (polyline
          (pts
            (xy 2.54 -17.78)
            (xy 3.175 -17.78)
          )
          (stroke (width 0) (type default))
          (fill (type none))
        )
        (polyline
          (pts
            (xy 2.54 -15.24)
            (xy 3.175 -15.24)
          )
          (stroke (width 0) (type default))
          (fill (type none))
        )
        (polyline
          (pts
            (xy 2.54 -12.7)
            (xy 3.175 -12.7)
          )
          (stroke (width 0) (type default))
          (fill (type none))
        )
        (polyline
          (pts
            (xy 2.54 -10.16)
            (xy 3.175 -10.16)
          )
          (stroke (width 0) (type default))
          (fill (type none))
        )
        (polyline
          (pts
            (xy 2.54 -7.62)
            (xy 3.175 -7.62)
          )
          (stroke (width 0) (type default))
          (fill (type none))
        )
        (polyline
          (pts
            (xy 2.54 -5.08)
            (xy 3.175 -5.08)
          )
          (stroke (width 0) (type default))
          (fill (type none))
        )
        (polyline
          (pts
            (xy 2.54 -2.54)
            (xy 3.175 -2.54)
          )
          (stroke (width 0) (type default))
          (fill (type none))
        )
        (polyline
          (pts
            (xy 2.54 0)
            (xy 3.175 0)
          )
          (stroke (width 0) (type default))
          (fill (type none))
        )
        (polyline
          (pts
            (xy 6.985 -17.78)
            (xy 7.62 -17.78)
          )
          (stroke (width 0) (type default))
          (fill (type none))
        )
        (polyline
          (pts
            (xy 6.985 -15.24)
            (xy 7.62 -15.24)
          )
          (stroke (width 0) (type default))
          (fill (type none))
        )
        (polyline
          (pts
            (xy 6.985 -12.7)
            (xy 7.62 -12.7)
          )
          (stroke (width 0) (type default))
          (fill (type none))
        )
        (polyline
          (pts
            (xy 6.985 -10.16)
            (xy 7.62 -10.16)
          )
          (stroke (width 0) (type default))
          (fill (type none))
        )
        (polyline
          (pts
            (xy 6.985 -7.62)
            (xy 7.62 -7.62)
          )
          (stroke (width 0) (type default))
          (fill (type none))
        )
        (polyline
          (pts
            (xy 6.985 -5.08)
            (xy 7.62 -5.08)
          )
          (stroke (width 0) (type default))
          (fill (type none))
        )
        (polyline
          (pts
            (xy 6.985 -2.54)
            (xy 7.62 -2.54)
          )
          (stroke (width 0) (type default))
          (fill (type none))
        )
        (polyline
          (pts
            (xy 6.985 0)
            (xy 7.62 0)
          )
          (stroke (width 0) (type default))
          (fill (type none))
        )
        (rectangle (start 2.667 1.27) (end 7.62 -19.05)
          (stroke (width 0.254) (type default))
          (fill (type background))
        )
        (rectangle (start 6.985 -17.145) (end 3.175 -18.415)
          (stroke (width 0.254) (type default))
          (fill (type none))
        )
        (rectangle (start 6.985 -14.605) (end 3.175 -15.875)
          (stroke (width 0.254) (type default))
          (fill (type none))
        )
        (rectangle (start 6.985 -12.065) (end 3.175 -13.335)
          (stroke (width 0.254) (type default))
          (fill (type none))
        )
        (rectangle (start 6.985 -9.525) (end 3.175 -10.795)
          (stroke (width 0.254) (type default))
          (fill (type none))
        )
        (rectangle (start 6.985 -6.985) (end 3.175 -8.255)
          (stroke (width 0.254) (type default))
          (fill (type none))
        )
        (rectangle (start 6.985 -4.445) (end 3.175 -5.715)
          (stroke (width 0.254) (type default))
          (fill (type none))
        )
        (rectangle (start 6.985 -1.905) (end 3.175 -3.175)
          (stroke (width 0.254) (type default))
          (fill (type none))
        )
        (rectangle (start 6.985 0.635) (end 3.175 -0.635)
          (stroke (width 0.254) (type default))
          (fill (type none))
        )
      )
      (symbol "8x51R_0602_array_1_1"
        (pin passive line (at 0 0 0) (length 2.54)
          (name "1" (effects (font (size 1.27 1.27))))
          (number "1" (effects (font (size 1.27 1.27))))
        )
        (pin passive line (at 10.16 -15.24 180) (length 2.54)
          (name "10" (effects (font (size 1.27 1.27))))
          (number "10" (effects (font (size 1.27 1.27))))
        )
        (pin passive line (at 10.16 -12.7 180) (length 2.54)
          (name "11" (effects (font (size 1.27 1.27))))
          (number "11" (effects (font (size 1.27 1.27))))
        )
        (pin passive line (at 10.16 -10.16 180) (length 2.54)
          (name "12" (effects (font (size 1.27 1.27))))
          (number "12" (effects (font (size 1.27 1.27))))
        )
        (pin passive line (at 10.16 -7.62 180) (length 2.54)
          (name "13" (effects (font (size 1.27 1.27))))
          (number "13" (effects (font (size 1.27 1.27))))
        )
        (pin passive line (at 10.16 -5.08 180) (length 2.54)
          (name "14" (effects (font (size 1.27 1.27))))
          (number "14" (effects (font (size 1.27 1.27))))
        )
        (pin passive line (at 10.16 -2.54 180) (length 2.54)
          (name "15" (effects (font (size 1.27 1.27))))
          (number "15" (effects (font (size 1.27 1.27))))
        )
        (pin passive line (at 10.16 0 180) (length 2.54)
          (name "16" (effects (font (size 1.27 1.27))))
          (number "16" (effects (font (size 1.27 1.27))))
        )
        (pin passive line (at 0 -2.54 0) (length 2.54)
          (name "2" (effects (font (size 1.27 1.27))))
          (number "2" (effects (font (size 1.27 1.27))))
        )
        (pin passive line (at 0 -5.08 0) (length 2.54)
          (name "3" (effects (font (size 1.27 1.27))))
          (number "3" (effects (font (size 1.27 1.27))))
        )
        (pin passive line (at 0 -7.62 0) (length 2.54)
          (name "4" (effects (font (size 1.27 1.27))))
          (number "4" (effects (font (size 1.27 1.27))))
        )
        (pin passive line (at 0 -10.16 0) (length 2.54)
          (name "5" (effects (font (size 1.27 1.27))))
          (number "5" (effects (font (size 1.27 1.27))))
        )
        (pin passive line (at 0 -12.7 0) (length 2.54)
          (name "6" (effects (font (size 1.27 1.27))))
          (number "6" (effects (font (size 1.27 1.27))))
        )
        (pin passive line (at 0 -15.24 0) (length 2.54)
          (name "7" (effects (font (size 1.27 1.27))))
          (number "7" (effects (font (size 1.27 1.27))))
        )
        (pin passive line (at 0 -17.78 0) (length 2.54)
          (name "8" (effects (font (size 1.27 1.27))))
          (number "8" (effects (font (size 1.27 1.27))))
        )
        (pin passive line (at 10.16 -17.78 180) (length 2.54)
          (name "9" (effects (font (size 1.27 1.27))))
          (number "9" (effects (font (size 1.27 1.27))))
        )
      )
    )
	(symbol "antmicroResistors0402:R_0R_0402" (pin_numbers hide) (pin_names hide) (in_bom yes) (on_board yes)
      (property "Reference" "R" (at 20.32 -5.08 0)
        (effects (font (size 1.27 1.27) (thickness 0.15)) (justify left bottom))
      )
      (property "Value" "R_0R_0402" (at 20.32 -12.7 0)
        (effects (font (size 1.27 1.27) (thickness 0.15)) (justify left bottom) hide)
      )
      (property "Footprint" "antmicro-footprints:R_0402_1005Metric" (at 20.32 -15.24 0)
        (effects (font (size 1.27 1.27) (thickness 0.15)) (justify left bottom) hide)
      )
      (property "Datasheet" "https://industrial.panasonic.com/cdbs/www-data/pdf/RDA0000/AOA0000C301.pdf" (at 20.32 -17.78 0)
        (effects (font (size 1.27 1.27) (thickness 0.15)) (justify left bottom) hide)
      )
      (property "MPN" "ERJ2GE0R00X" (at 20.32 -20.32 0)
        (effects (font (size 1.27 1.27) (thickness 0.15)) (justify left bottom) hide)
      )
      (property "Manufacturer" "Panasonic" (at 20.32 -22.86 0)
        (effects (font (size 1.27 1.27) (thickness 0.15)) (justify left bottom) hide)
      )
      (property "License" "Apache-2.0" (at 20.32 -25.4 0)
        (effects (font (size 1.27 1.27) (thickness 0.15)) (justify left bottom) hide)
      )
      (property "Author" "Antmicro" (at 20.32 -27.94 0)
        (effects (font (size 1.27 1.27) (thickness 0.15)) (justify left bottom) hide)
      )
      (property "Val" "0R" (at 20.32 -7.62 0)
        (effects (font (size 1.27 1.27) (thickness 0.15)) (justify left bottom))
      )
      (property "Tolerance" "~" (at 20.32 -10.16 0)
        (effects (font (size 1.27 1.27)) (justify left bottom) hide)
      )
      (property "Current" "1A" (at 20.32 -30.48 0)
        (effects (font (size 1.27 1.27) (thickness 0.15)) (justify left bottom) hide)
      )
      (property "ki_keywords" "0402, SMT, RESISTOR, PASSIVE" (at 0 0 0)
        (effects (font (size 1.27 1.27)) hide)
      )
      (property "ki_description" "SMD Chip Resistor, Jumper, 0 ohm, 100 mW, 0402 [1005 Metric], Thick Film, General Purpose" (at 0 0 0)
        (effects (font (size 1.27 1.27)) hide)
      )
      (symbol "R_0R_0402_0_1"
        (rectangle (start 0.635 0.889) (end 4.445 -0.889)
          (stroke (width 0.254) (type default))
          (fill (type none))
        )
      )
      (symbol "R_0R_0402_1_1"
        (pin passive line (at 0 0 0) (length 0.635)
          (name "~" (effects (font (size 1.27 1.27))))
          (number "1" (effects (font (size 1.27 1.27))))
        )
        (pin passive line (at 5.08 0 180) (length 0.635)
          (name "~" (effects (font (size 1.27 1.27))))
          (number "2" (effects (font (size 1.27 1.27))))
        )
      )
    )
	(symbol "antmicroResistors0402:R_100k_0402" (pin_numbers hide) (pin_names hide) (in_bom yes) (on_board yes)
      (property "Reference" "R" (at 20.32 -5.08 0)
        (effects (font (size 1.27 1.27) (thickness 0.15)) (justify left bottom))
      )
      (property "Value" "R_100k_0402" (at 20.32 -12.7 0)
        (effects (font (size 1.27 1.27) (thickness 0.15)) (justify left bottom) hide)
      )
      (property "Footprint" "antmicro-footprints:R_0402_1005Metric" (at 20.32 -15.24 0)
        (effects (font (size 1.27 1.27) (thickness 0.15)) (justify left bottom) hide)
      )
      (property "Datasheet" "https://www.bourns.com/docs/product-datasheets/cr.pdf" (at 20.32 -17.78 0)
        (effects (font (size 1.27 1.27) (thickness 0.15)) (justify left bottom) hide)
      )
      (property "MPN" "CR0402-FX-1003GLF" (at 20.32 -20.32 0)
        (effects (font (size 1.27 1.27) (thickness 0.15)) (justify left bottom) hide)
      )
      (property "Manufacturer" "Bourns" (at 20.32 -22.86 0)
        (effects (font (size 1.27 1.27) (thickness 0.15)) (justify left bottom) hide)
      )
      (property "License" "Apache-2.0" (at 20.32 -25.4 0)
        (effects (font (size 1.27 1.27) (thickness 0.15)) (justify left bottom) hide)
      )
      (property "Author" "Antmicro" (at 20.32 -27.94 0)
        (effects (font (size 1.27 1.27) (thickness 0.15)) (justify left bottom) hide)
      )
      (property "Val" "100k" (at 20.32 -7.62 0)
        (effects (font (size 1.27 1.27) (thickness 0.15)) (justify left bottom))
      )
      (property "Tolerance" "1%" (at 20.32 -10.16 0)
        (effects (font (size 1.27 1.27)) (justify left bottom) hide)
      )
      (property "ki_keywords" "0402, SMT, RESISTOR, PASSIVE" (at 0 0 0)
        (effects (font (size 1.27 1.27)) hide)
      )
      (property "ki_description" "SMD Chip Resistor, 100 kohm, ± 1%, 62.5 mW, 0402 [1005 Metric], Thick Film, General Purpose" (at 0 0 0)
        (effects (font (size 1.27 1.27)) hide)
      )
      (symbol "R_100k_0402_0_1"
        (rectangle (start 0.635 0.889) (end 4.445 -0.889)
          (stroke (width 0.254) (type default))
          (fill (type none))
        )
      )
      (symbol "R_100k_0402_1_1"
        (pin passive line (at 0 0 0) (length 0.635)
          (name "~" (effects (font (size 1.27 1.27))))
          (number "1" (effects (font (size 1.27 1.27))))
        )
        (pin passive line (at 5.08 0 180) (length 0.635)
          (name "~" (effects (font (size 1.27 1.27))))
          (number "2" (effects (font (size 1.27 1.27))))
        )
      )
    )
	(symbol "antmicroResistors0402:R_10k2_0402" (pin_numbers hide) (pin_names hide) (in_bom yes) (on_board yes)
      (property "Reference" "R" (at 20.32 -5.08 0)
        (effects (font (size 1.27 1.27) (thickness 0.15)) (justify left bottom))
      )
      (property "Value" "R_10k2_0402" (at 20.32 -12.7 0)
        (effects (font (size 1.27 1.27) (thickness 0.15)) (justify left bottom) hide)
      )
      (property "Footprint" "antmicro-footprints:R_0402_1005Metric" (at 20.32 -15.24 0)
        (effects (font (size 1.27 1.27) (thickness 0.15)) (justify left bottom) hide)
      )
      (property "Datasheet" "https://www.bourns.com/docs/product-datasheets/cr.pdf" (at 20.32 -17.78 0)
        (effects (font (size 1.27 1.27) (thickness 0.15)) (justify left bottom) hide)
      )
      (property "MPN" "CR0402-FX-1022GLF" (at 20.32 -20.32 0)
        (effects (font (size 1.27 1.27) (thickness 0.15)) (justify left bottom) hide)
      )
      (property "Manufacturer" "Bourns" (at 20.32 -22.86 0)
        (effects (font (size 1.27 1.27) (thickness 0.15)) (justify left bottom) hide)
      )
      (property "License" "Apache-2.0" (at 20.32 -25.4 0)
        (effects (font (size 1.27 1.27) (thickness 0.15)) (justify left bottom) hide)
      )
      (property "Author" "Antmicro" (at 20.32 -27.94 0)
        (effects (font (size 1.27 1.27) (thickness 0.15)) (justify left bottom) hide)
      )
      (property "Val" "10k2" (at 20.32 -7.62 0)
        (effects (font (size 1.27 1.27) (thickness 0.15)) (justify left bottom))
      )
      (property "Tolerance" "1%" (at 20.32 -10.16 0)
        (effects (font (size 1.27 1.27)) (justify left bottom) hide)
      )
      (property "ki_keywords" "0402, SMT, RESISTOR, PASSIVE" (at 0 0 0)
        (effects (font (size 1.27 1.27)) hide)
      )
      (property "ki_description" "SMD Chip Resistor" (at 0 0 0)
        (effects (font (size 1.27 1.27)) hide)
      )
      (symbol "R_10k2_0402_0_1"
        (rectangle (start 0.635 0.889) (end 4.445 -0.889)
          (stroke (width 0.254) (type default))
          (fill (type none))
        )
      )
      (symbol "R_10k2_0402_1_1"
        (pin passive line (at 0 0 0) (length 0.635)
          (name "~" (effects (font (size 1.27 1.27))))
          (number "1" (effects (font (size 1.27 1.27))))
        )
        (pin passive line (at 5.08 0 180) (length 0.635)
          (name "~" (effects (font (size 1.27 1.27))))
          (number "2" (effects (font (size 1.27 1.27))))
        )
      )
    )
	(symbol "antmicroResistors0402:R_10k_0402" (pin_numbers hide) (pin_names hide) (in_bom yes) (on_board yes)
      (property "Reference" "R" (at 20.32 -5.08 0)
        (effects (font (size 1.27 1.27) (thickness 0.15)) (justify left bottom))
      )
      (property "Value" "R_10k_0402" (at 20.32 -12.7 0)
        (effects (font (size 1.27 1.27) (thickness 0.15)) (justify left bottom) hide)
      )
      (property "Footprint" "antmicro-footprints:R_0402_1005Metric" (at 20.32 -15.24 0)
        (effects (font (size 1.27 1.27) (thickness 0.15)) (justify left bottom) hide)
      )
      (property "Datasheet" "https://www.bourns.com/docs/product-datasheets/cr.pdf" (at 20.32 -17.78 0)
        (effects (font (size 1.27 1.27) (thickness 0.15)) (justify left bottom) hide)
      )
      (property "MPN" "CR0402-FX-1002GLF" (at 20.32 -20.32 0)
        (effects (font (size 1.27 1.27) (thickness 0.15)) (justify left bottom) hide)
      )
      (property "Manufacturer" "Bourns" (at 20.32 -22.86 0)
        (effects (font (size 1.27 1.27) (thickness 0.15)) (justify left bottom) hide)
      )
      (property "License" "Apache-2.0" (at 20.32 -25.4 0)
        (effects (font (size 1.27 1.27) (thickness 0.15)) (justify left bottom) hide)
      )
      (property "Author" "Antmicro" (at 20.32 -27.94 0)
        (effects (font (size 1.27 1.27) (thickness 0.15)) (justify left bottom) hide)
      )
      (property "Val" "10k" (at 20.32 -7.62 0)
        (effects (font (size 1.27 1.27) (thickness 0.15)) (justify left bottom))
      )
      (property "Tolerance" "1%" (at 20.32 -10.16 0)
        (effects (font (size 1.27 1.27)) (justify left bottom) hide)
      )
      (property "ki_keywords" "0402, SMT, RESISTOR, PASSIVE" (at 0 0 0)
        (effects (font (size 1.27 1.27)) hide)
      )
      (property "ki_description" "SMD Chip Resistor, 10 kohm, ± 1%, 62.5 mW, 0402 [1005 Metric], Thick Film, General Purpose" (at 0 0 0)
        (effects (font (size 1.27 1.27)) hide)
      )
      (symbol "R_10k_0402_0_1"
        (rectangle (start 0.635 0.889) (end 4.445 -0.889)
          (stroke (width 0.254) (type default))
          (fill (type none))
        )
      )
      (symbol "R_10k_0402_1_1"
        (pin passive line (at 0 0 0) (length 0.635)
          (name "~" (effects (font (size 1.27 1.27))))
          (number "1" (effects (font (size 1.27 1.27))))
        )
        (pin passive line (at 5.08 0 180) (length 0.635)
          (name "~" (effects (font (size 1.27 1.27))))
          (number "2" (effects (font (size 1.27 1.27))))
        )
      )
    )
	(symbol "antmicroResistors0402:R_124k_0402" (pin_numbers hide) (pin_names hide) (in_bom yes) (on_board yes)
      (property "Reference" "R" (at 20.32 -5.08 0)
        (effects (font (size 1.27 1.27) (thickness 0.15)) (justify left bottom))
      )
      (property "Value" "R_124k_0402" (at 20.32 -12.7 0)
        (effects (font (size 1.27 1.27) (thickness 0.15)) (justify left bottom) hide)
      )
      (property "Footprint" "antmicro-footprints:R_0402_1005Metric" (at 20.32 -15.24 0)
        (effects (font (size 1.27 1.27) (thickness 0.15)) (justify left bottom) hide)
      )
      (property "Datasheet" "https://www.bourns.com/docs/product-datasheets/cr.pdf" (at 20.32 -17.78 0)
        (effects (font (size 1.27 1.27) (thickness 0.15)) (justify left bottom) hide)
      )
      (property "MPN" "CR0402-FX-1243GLF" (at 20.32 -20.32 0)
        (effects (font (size 1.27 1.27) (thickness 0.15)) (justify left bottom) hide)
      )
      (property "Manufacturer" "Bourns" (at 20.32 -22.86 0)
        (effects (font (size 1.27 1.27) (thickness 0.15)) (justify left bottom) hide)
      )
      (property "License" "Apache-2.0" (at 20.32 -25.4 0)
        (effects (font (size 1.27 1.27) (thickness 0.15)) (justify left bottom) hide)
      )
      (property "Author" "Antmicro" (at 20.32 -27.94 0)
        (effects (font (size 1.27 1.27) (thickness 0.15)) (justify left bottom) hide)
      )
      (property "Val" "124k" (at 20.32 -7.62 0)
        (effects (font (size 1.27 1.27) (thickness 0.15)) (justify left bottom))
      )
      (property "Tolerance" "1%" (at 20.32 -10.16 0)
        (effects (font (size 1.27 1.27)) (justify left bottom) hide)
      )
      (property "ki_keywords" "0402, SMT, RESISTOR, PASSIVE" (at 0 0 0)
        (effects (font (size 1.27 1.27)) hide)
      )
      (property "ki_description" "SMD Chip Resistor, 124 kohm, ± 1%, 100 mW, 0402 [1005 Metric], Thick Film, Precision" (at 0 0 0)
        (effects (font (size 1.27 1.27)) hide)
      )
      (symbol "R_124k_0402_0_1"
        (rectangle (start 0.635 0.889) (end 4.445 -0.889)
          (stroke (width 0.254) (type default))
          (fill (type none))
        )
      )
      (symbol "R_124k_0402_1_1"
        (pin passive line (at 0 0 0) (length 0.635)
          (name "~" (effects (font (size 1.27 1.27))))
          (number "1" (effects (font (size 1.27 1.27))))
        )
        (pin passive line (at 5.08 0 180) (length 0.635)
          (name "~" (effects (font (size 1.27 1.27))))
          (number "2" (effects (font (size 1.27 1.27))))
        )
      )
    )
	(symbol "antmicroResistors0402:R_12k1_0402" (pin_numbers hide) (pin_names hide) (in_bom yes) (on_board yes)
      (property "Reference" "R" (at 20.32 -5.08 0)
        (effects (font (size 1.27 1.27) (thickness 0.15)) (justify left bottom))
      )
      (property "Value" "R_12k1_0402" (at 20.32 -12.7 0)
        (effects (font (size 1.27 1.27) (thickness 0.15)) (justify left bottom) hide)
      )
      (property "Footprint" "antmicro-footprints:R_0402_1005Metric" (at 20.32 -15.24 0)
        (effects (font (size 1.27 1.27) (thickness 0.15)) (justify left bottom) hide)
      )
      (property "Datasheet" "https://www.bourns.com/docs/product-datasheets/cr.pdf" (at 20.32 -17.78 0)
        (effects (font (size 1.27 1.27) (thickness 0.15)) (justify left bottom) hide)
      )
      (property "MPN" "CR0402-FX-1212GLF" (at 20.32 -20.32 0)
        (effects (font (size 1.27 1.27) (thickness 0.15)) (justify left bottom) hide)
      )
      (property "Manufacturer" "Bourns" (at 20.32 -22.86 0)
        (effects (font (size 1.27 1.27) (thickness 0.15)) (justify left bottom) hide)
      )
      (property "License" "Apache-2.0" (at 20.32 -25.4 0)
        (effects (font (size 1.27 1.27) (thickness 0.15)) (justify left bottom) hide)
      )
      (property "Author" "Antmicro" (at 20.32 -27.94 0)
        (effects (font (size 1.27 1.27) (thickness 0.15)) (justify left bottom) hide)
      )
      (property "Val" "12k1" (at 20.32 -7.62 0)
        (effects (font (size 1.27 1.27) (thickness 0.15)) (justify left bottom))
      )
      (property "Tolerance" "1%" (at 20.32 -10.16 0)
        (effects (font (size 1.27 1.27)) (justify left bottom) hide)
      )
      (property "ki_keywords" "0402, SMT, RESISTOR, PASSIVE" (at 0 0 0)
        (effects (font (size 1.27 1.27)) hide)
      )
      (property "ki_description" "SMD Chip Resistor, 12.1 kohm, ± 1%, 62.5 mW, 0402 [1005 Metric], Thick Film, General Purpose" (at 0 0 0)
        (effects (font (size 1.27 1.27)) hide)
      )
      (symbol "R_12k1_0402_0_1"
        (rectangle (start 0.635 0.889) (end 4.445 -0.889)
          (stroke (width 0.254) (type default))
          (fill (type none))
        )
      )
      (symbol "R_12k1_0402_1_1"
        (pin passive line (at 0 0 0) (length 0.635)
          (name "~" (effects (font (size 1.27 1.27))))
          (number "1" (effects (font (size 1.27 1.27))))
        )
        (pin passive line (at 5.08 0 180) (length 0.635)
          (name "~" (effects (font (size 1.27 1.27))))
          (number "2" (effects (font (size 1.27 1.27))))
        )
      )
    )
	(symbol "antmicroResistors0402:R_12k_0402" (pin_numbers hide) (pin_names hide) (in_bom yes) (on_board yes)
      (property "Reference" "R" (at 20.32 -5.08 0)
        (effects (font (size 1.27 1.27) (thickness 0.15)) (justify left bottom))
      )
      (property "Value" "R_12k_0402" (at 20.32 -12.7 0)
        (effects (font (size 1.27 1.27) (thickness 0.15)) (justify left bottom) hide)
      )
      (property "Footprint" "antmicro-footprints:R_0402_1005Metric" (at 20.32 -15.24 0)
        (effects (font (size 1.27 1.27) (thickness 0.15)) (justify left bottom) hide)
      )
      (property "Datasheet" "https://www.bourns.com/docs/product-datasheets/cr.pdf" (at 20.32 -17.78 0)
        (effects (font (size 1.27 1.27) (thickness 0.15)) (justify left bottom) hide)
      )
      (property "MPN" "CR0402-FX-1202GLF" (at 20.32 -20.32 0)
        (effects (font (size 1.27 1.27) (thickness 0.15)) (justify left bottom) hide)
      )
      (property "Manufacturer" "Bourns" (at 20.32 -22.86 0)
        (effects (font (size 1.27 1.27) (thickness 0.15)) (justify left bottom) hide)
      )
      (property "License" "Apache-2.0" (at 20.32 -25.4 0)
        (effects (font (size 1.27 1.27) (thickness 0.15)) (justify left bottom) hide)
      )
      (property "Author" "Antmicro" (at 20.32 -27.94 0)
        (effects (font (size 1.27 1.27) (thickness 0.15)) (justify left bottom) hide)
      )
      (property "Val" "12k" (at 20.32 -7.62 0)
        (effects (font (size 1.27 1.27) (thickness 0.15)) (justify left bottom))
      )
      (property "Tolerance" "1%" (at 20.32 -10.16 0)
        (effects (font (size 1.27 1.27)) (justify left bottom) hide)
      )
      (property "ki_keywords" "0402, SMT, RESISTOR, PASSIVE" (at 0 0 0)
        (effects (font (size 1.27 1.27)) hide)
      )
      (property "ki_description" "SMD Chip Resistor, 12 kohm, ± 1%, 62.5 mW, 0402 [1005 Metric], Thick Film, General Purpose" (at 0 0 0)
        (effects (font (size 1.27 1.27)) hide)
      )
      (symbol "R_12k_0402_0_1"
        (rectangle (start 0.635 0.889) (end 4.445 -0.889)
          (stroke (width 0.254) (type default))
          (fill (type none))
        )
      )
      (symbol "R_12k_0402_1_1"
        (pin passive line (at 0 0 0) (length 0.635)
          (name "~" (effects (font (size 1.27 1.27))))
          (number "1" (effects (font (size 1.27 1.27))))
        )
        (pin passive line (at 5.08 0 180) (length 0.635)
          (name "~" (effects (font (size 1.27 1.27))))
          (number "2" (effects (font (size 1.27 1.27))))
        )
      )
    )
	(symbol "antmicroResistors0402:R_16k9_0402" (pin_numbers hide) (pin_names hide) (in_bom yes) (on_board yes)
      (property "Reference" "R" (at 20.32 -5.08 0)
        (effects (font (size 1.27 1.27) (thickness 0.15)) (justify left bottom))
      )
      (property "Value" "R_16k9_0402" (at 20.32 -12.7 0)
        (effects (font (size 1.27 1.27) (thickness 0.15)) (justify left bottom) hide)
      )
      (property "Footprint" "antmicro-footprints:R_0402_1005Metric" (at 20.32 -15.24 0)
        (effects (font (size 1.27 1.27) (thickness 0.15)) (justify left bottom) hide)
      )
      (property "Datasheet" "https://www.bourns.com/docs/product-datasheets/cr.pdf" (at 20.32 -17.78 0)
        (effects (font (size 1.27 1.27) (thickness 0.15)) (justify left bottom) hide)
      )
      (property "MPN" "CR0402-FX-1692GLF" (at 20.32 -20.32 0)
        (effects (font (size 1.27 1.27) (thickness 0.15)) (justify left bottom) hide)
      )
      (property "Manufacturer" "Bourns" (at 20.32 -22.86 0)
        (effects (font (size 1.27 1.27) (thickness 0.15)) (justify left bottom) hide)
      )
      (property "License" "Apache-2.0" (at 20.32 -25.4 0)
        (effects (font (size 1.27 1.27) (thickness 0.15)) (justify left bottom) hide)
      )
      (property "Author" "Antmicro" (at 20.32 -27.94 0)
        (effects (font (size 1.27 1.27) (thickness 0.15)) (justify left bottom) hide)
      )
      (property "Val" "16k9" (at 20.32 -7.62 0)
        (effects (font (size 1.27 1.27) (thickness 0.15)) (justify left bottom))
      )
      (property "Tolerance" "1%" (at 20.32 -10.16 0)
        (effects (font (size 1.27 1.27)) (justify left bottom) hide)
      )
      (property "ki_keywords" "0402, SMT, RESISTOR, PASSIVE" (at 0 0 0)
        (effects (font (size 1.27 1.27)) hide)
      )
      (property "ki_description" "SMD Chip Resistor, Ceramic, 16.9 kohm, ± 1%, 62.5 mW, 0402 [1005 Metric], Thick Film" (at 0 0 0)
        (effects (font (size 1.27 1.27)) hide)
      )
      (symbol "R_16k9_0402_0_1"
        (rectangle (start 0.635 0.889) (end 4.445 -0.889)
          (stroke (width 0.254) (type default))
          (fill (type none))
        )
      )
      (symbol "R_16k9_0402_1_1"
        (pin passive line (at 0 0 0) (length 0.635)
          (name "~" (effects (font (size 1.27 1.27))))
          (number "1" (effects (font (size 1.27 1.27))))
        )
        (pin passive line (at 5.08 0 180) (length 0.635)
          (name "~" (effects (font (size 1.27 1.27))))
          (number "2" (effects (font (size 1.27 1.27))))
        )
      )
    )
	(symbol "antmicroResistors0402:R_1k1_0402" (pin_numbers hide) (pin_names hide) (in_bom yes) (on_board yes)
      (property "Reference" "R" (at 20.32 -5.08 0)
        (effects (font (size 1.27 1.27) (thickness 0.15)) (justify left bottom))
      )
      (property "Value" "R_1k1_0402" (at 20.32 -12.7 0)
        (effects (font (size 1.27 1.27) (thickness 0.15)) (justify left bottom) hide)
      )
      (property "Footprint" "antmicro-footprints:R_0402_1005Metric" (at 20.32 -15.24 0)
        (effects (font (size 1.27 1.27) (thickness 0.15)) (justify left bottom) hide)
      )
      (property "Datasheet" "https://www.bourns.com/docs/product-datasheets/cr.pdf" (at 20.32 -17.78 0)
        (effects (font (size 1.27 1.27) (thickness 0.15)) (justify left bottom) hide)
      )
      (property "MPN" "CR0402-FX-1101GLF" (at 20.32 -20.32 0)
        (effects (font (size 1.27 1.27) (thickness 0.15)) (justify left bottom) hide)
      )
      (property "Manufacturer" "Bourns" (at 20.32 -22.86 0)
        (effects (font (size 1.27 1.27) (thickness 0.15)) (justify left bottom) hide)
      )
      (property "License" "Apache-2.0" (at 20.32 -25.4 0)
        (effects (font (size 1.27 1.27) (thickness 0.15)) (justify left bottom) hide)
      )
      (property "Author" "Antmicro" (at 20.32 -27.94 0)
        (effects (font (size 1.27 1.27) (thickness 0.15)) (justify left bottom) hide)
      )
      (property "Val" "1k1" (at 20.32 -7.62 0)
        (effects (font (size 1.27 1.27) (thickness 0.15)) (justify left bottom))
      )
      (property "Tolerance" "1%" (at 20.32 -10.16 0)
        (effects (font (size 1.27 1.27)) (justify left bottom) hide)
      )
      (property "ki_keywords" "0402, SMT, RESISTOR, PASSIVE" (at 0 0 0)
        (effects (font (size 1.27 1.27)) hide)
      )
      (property "ki_description" "SMD Chip Resistor" (at 0 0 0)
        (effects (font (size 1.27 1.27)) hide)
      )
      (symbol "R_1k1_0402_0_1"
        (rectangle (start 0.635 0.889) (end 4.445 -0.889)
          (stroke (width 0.254) (type default))
          (fill (type none))
        )
      )
      (symbol "R_1k1_0402_1_1"
        (pin passive line (at 0 0 0) (length 0.635)
          (name "~" (effects (font (size 1.27 1.27))))
          (number "1" (effects (font (size 1.27 1.27))))
        )
        (pin passive line (at 5.08 0 180) (length 0.635)
          (name "~" (effects (font (size 1.27 1.27))))
          (number "2" (effects (font (size 1.27 1.27))))
        )
      )
    )
	(symbol "antmicroResistors0402:R_1k_0402" (pin_numbers hide) (pin_names hide) (in_bom yes) (on_board yes)
      (property "Reference" "R" (at 20.32 -5.08 0)
        (effects (font (size 1.27 1.27) (thickness 0.15)) (justify left bottom))
      )
      (property "Value" "R_1k_0402" (at 20.32 -12.7 0)
        (effects (font (size 1.27 1.27) (thickness 0.15)) (justify left bottom) hide)
      )
      (property "Footprint" "antmicro-footprints:R_0402_1005Metric" (at 20.32 -15.24 0)
        (effects (font (size 1.27 1.27) (thickness 0.15)) (justify left bottom) hide)
      )
      (property "Datasheet" "https://www.bourns.com/docs/product-datasheets/cr.pdf" (at 20.32 -17.78 0)
        (effects (font (size 1.27 1.27) (thickness 0.15)) (justify left bottom) hide)
      )
      (property "MPN" "CR0402-FX-1001GLF" (at 20.32 -20.32 0)
        (effects (font (size 1.27 1.27) (thickness 0.15)) (justify left bottom) hide)
      )
      (property "Manufacturer" "Bourns" (at 20.32 -22.86 0)
        (effects (font (size 1.27 1.27) (thickness 0.15)) (justify left bottom) hide)
      )
      (property "License" "Apache-2.0" (at 20.32 -25.4 0)
        (effects (font (size 1.27 1.27) (thickness 0.15)) (justify left bottom) hide)
      )
      (property "Author" "Antmicro" (at 20.32 -27.94 0)
        (effects (font (size 1.27 1.27) (thickness 0.15)) (justify left bottom) hide)
      )
      (property "Val" "1k" (at 20.32 -7.62 0)
        (effects (font (size 1.27 1.27) (thickness 0.15)) (justify left bottom))
      )
      (property "Tolerance" "1%" (at 20.32 -10.16 0)
        (effects (font (size 1.27 1.27)) (justify left bottom) hide)
      )
      (property "ki_keywords" "0402, SMT, RESISTOR, PASSIVE" (at 0 0 0)
        (effects (font (size 1.27 1.27)) hide)
      )
      (property "ki_description" "SMD Chip Resistor, 1 kohm, ± 1%, 63 mW, 0402 [1005 Metric], Thick Film, General Purpose" (at 0 0 0)
        (effects (font (size 1.27 1.27)) hide)
      )
      (symbol "R_1k_0402_0_1"
        (rectangle (start 0.635 0.889) (end 4.445 -0.889)
          (stroke (width 0.254) (type default))
          (fill (type none))
        )
      )
      (symbol "R_1k_0402_1_1"
        (pin passive line (at 0 0 0) (length 0.635)
          (name "~" (effects (font (size 1.27 1.27))))
          (number "1" (effects (font (size 1.27 1.27))))
        )
        (pin passive line (at 5.08 0 180) (length 0.635)
          (name "~" (effects (font (size 1.27 1.27))))
          (number "2" (effects (font (size 1.27 1.27))))
        )
      )
    )
	(symbol "antmicroResistors0402:R_200k_0402" (pin_numbers hide) (pin_names hide) (in_bom yes) (on_board yes)
      (property "Reference" "R" (at 20.32 -5.08 0)
        (effects (font (size 1.27 1.27) (thickness 0.15)) (justify left bottom))
      )
      (property "Value" "R_200k_0402" (at 20.32 -12.7 0)
        (effects (font (size 1.27 1.27) (thickness 0.15)) (justify left bottom) hide)
      )
      (property "Footprint" "antmicro-footprints:R_0402_1005Metric" (at 20.32 -15.24 0)
        (effects (font (size 1.27 1.27) (thickness 0.15)) (justify left bottom) hide)
      )
      (property "Datasheet" "https://www.bourns.com/docs/product-datasheets/cr.pdf" (at 20.32 -17.78 0)
        (effects (font (size 1.27 1.27) (thickness 0.15)) (justify left bottom) hide)
      )
      (property "MPN" "CR0402-FX-2003GLF" (at 20.32 -20.32 0)
        (effects (font (size 1.27 1.27) (thickness 0.15)) (justify left bottom) hide)
      )
      (property "Manufacturer" "Bourns" (at 20.32 -22.86 0)
        (effects (font (size 1.27 1.27) (thickness 0.15)) (justify left bottom) hide)
      )
      (property "License" "Apache-2.0" (at 20.32 -25.4 0)
        (effects (font (size 1.27 1.27) (thickness 0.15)) (justify left bottom) hide)
      )
      (property "Author" "Antmicro" (at 20.32 -27.94 0)
        (effects (font (size 1.27 1.27) (thickness 0.15)) (justify left bottom) hide)
      )
      (property "Val" "200k" (at 20.32 -7.62 0)
        (effects (font (size 1.27 1.27) (thickness 0.15)) (justify left bottom))
      )
      (property "Tolerance" "1%" (at 20.32 -10.16 0)
        (effects (font (size 1.27 1.27)) (justify left bottom) hide)
      )
      (property "ki_keywords" "0402, SMT, RESISTOR, PASSIVE" (at 0 0 0)
        (effects (font (size 1.27 1.27)) hide)
      )
      (property "ki_description" "SMD Chip Resistor, 200 kohm, ± 1%, 62.5 mW, 0402 [1005 Metric], Thick Film, General Purpose" (at 0 0 0)
        (effects (font (size 1.27 1.27)) hide)
      )
      (symbol "R_200k_0402_0_1"
        (rectangle (start 0.635 0.889) (end 4.445 -0.889)
          (stroke (width 0.254) (type default))
          (fill (type none))
        )
      )
      (symbol "R_200k_0402_1_1"
        (pin passive line (at 0 0 0) (length 0.635)
          (name "~" (effects (font (size 1.27 1.27))))
          (number "1" (effects (font (size 1.27 1.27))))
        )
        (pin passive line (at 5.08 0 180) (length 0.635)
          (name "~" (effects (font (size 1.27 1.27))))
          (number "2" (effects (font (size 1.27 1.27))))
        )
      )
    )
	(symbol "antmicroResistors0402:R_22R_0402" (pin_numbers hide) (pin_names hide) (in_bom yes) (on_board yes)
      (property "Reference" "R" (at 20.32 -5.08 0)
        (effects (font (size 1.27 1.27) (thickness 0.15)) (justify left bottom))
      )
      (property "Value" "R_22R_0402" (at 20.32 -12.7 0)
        (effects (font (size 1.27 1.27) (thickness 0.15)) (justify left bottom) hide)
      )
      (property "Footprint" "antmicro-footprints:R_0402_1005Metric" (at 20.32 -15.24 0)
        (effects (font (size 1.27 1.27) (thickness 0.15)) (justify left bottom) hide)
      )
      (property "Datasheet" "https://www.bourns.com/docs/product-datasheets/cr.pdf" (at 20.32 -17.78 0)
        (effects (font (size 1.27 1.27) (thickness 0.15)) (justify left bottom) hide)
      )
      (property "MPN" "CR0402-FX-22R0GLF" (at 20.32 -20.32 0)
        (effects (font (size 1.27 1.27) (thickness 0.15)) (justify left bottom) hide)
      )
      (property "Manufacturer" "Bourns" (at 20.32 -22.86 0)
        (effects (font (size 1.27 1.27) (thickness 0.15)) (justify left bottom) hide)
      )
      (property "License" "Apache-2.0" (at 20.32 -25.4 0)
        (effects (font (size 1.27 1.27) (thickness 0.15)) (justify left bottom) hide)
      )
      (property "Author" "Antmicro" (at 20.32 -27.94 0)
        (effects (font (size 1.27 1.27) (thickness 0.15)) (justify left bottom) hide)
      )
      (property "Val" "22R" (at 20.32 -7.62 0)
        (effects (font (size 1.27 1.27) (thickness 0.15)) (justify left bottom))
      )
      (property "Tolerance" "1%" (at 20.32 -10.16 0)
        (effects (font (size 1.27 1.27)) (justify left bottom) hide)
      )
      (property "ki_keywords" "0402, SMT, RESISTOR, PASSIVE" (at 0 0 0)
        (effects (font (size 1.27 1.27)) hide)
      )
      (property "ki_description" "SMD Chip Resistor, 22 ohm, ± 1%, 62.5 mW, 0402 [1005 Metric], Thick Film, General Purpose" (at 0 0 0)
        (effects (font (size 1.27 1.27)) hide)
      )
      (symbol "R_22R_0402_0_1"
        (rectangle (start 0.635 0.889) (end 4.445 -0.889)
          (stroke (width 0.254) (type default))
          (fill (type none))
        )
      )
      (symbol "R_22R_0402_1_1"
        (pin passive line (at 0 0 0) (length 0.635)
          (name "~" (effects (font (size 1.27 1.27))))
          (number "1" (effects (font (size 1.27 1.27))))
        )
        (pin passive line (at 5.08 0 180) (length 0.635)
          (name "~" (effects (font (size 1.27 1.27))))
          (number "2" (effects (font (size 1.27 1.27))))
        )
      )
    )
	(symbol "antmicroResistors0402:R_240R_0402" (pin_numbers hide) (pin_names hide) (in_bom yes) (on_board yes)
      (property "Reference" "R" (at 20.32 -5.08 0)
        (effects (font (size 1.27 1.27) (thickness 0.15)) (justify left bottom))
      )
      (property "Value" "R_240R_0402" (at 20.32 -12.7 0)
        (effects (font (size 1.27 1.27) (thickness 0.15)) (justify left bottom) hide)
      )
      (property "Footprint" "antmicro-footprints:R_0402_1005Metric" (at 20.32 -15.24 0)
        (effects (font (size 1.27 1.27) (thickness 0.15)) (justify left bottom) hide)
      )
      (property "Datasheet" "https://www.bourns.com/docs/product-datasheets/cr.pdf" (at 20.32 -17.78 0)
        (effects (font (size 1.27 1.27) (thickness 0.15)) (justify left bottom) hide)
      )
      (property "MPN" "CR0402-FX-2400GLF" (at 20.32 -20.32 0)
        (effects (font (size 1.27 1.27) (thickness 0.15)) (justify left bottom) hide)
      )
      (property "Manufacturer" "Bourns" (at 20.32 -22.86 0)
        (effects (font (size 1.27 1.27) (thickness 0.15)) (justify left bottom) hide)
      )
      (property "License" "Apache-2.0" (at 20.32 -25.4 0)
        (effects (font (size 1.27 1.27) (thickness 0.15)) (justify left bottom) hide)
      )
      (property "Author" "Antmicro" (at 20.32 -27.94 0)
        (effects (font (size 1.27 1.27) (thickness 0.15)) (justify left bottom) hide)
      )
      (property "Val" "240R" (at 20.32 -7.62 0)
        (effects (font (size 1.27 1.27) (thickness 0.15)) (justify left bottom))
      )
      (property "Tolerance" "1%" (at 20.32 -10.16 0)
        (effects (font (size 1.27 1.27)) (justify left bottom) hide)
      )
      (property "ki_keywords" "0402, SMT, RESISTOR, PASSIVE" (at 0 0 0)
        (effects (font (size 1.27 1.27)) hide)
      )
      (property "ki_description" "SMD Chip Resistor, 240 ohm, ± 1%, 63 mW, 0402 [1005 Metric], Thick Film, General Purpose" (at 0 0 0)
        (effects (font (size 1.27 1.27)) hide)
      )
      (symbol "R_240R_0402_0_1"
        (rectangle (start 0.635 0.889) (end 4.445 -0.889)
          (stroke (width 0.254) (type default))
          (fill (type none))
        )
      )
      (symbol "R_240R_0402_1_1"
        (pin passive line (at 0 0 0) (length 0.635)
          (name "~" (effects (font (size 1.27 1.27))))
          (number "1" (effects (font (size 1.27 1.27))))
        )
        (pin passive line (at 5.08 0 180) (length 0.635)
          (name "~" (effects (font (size 1.27 1.27))))
          (number "2" (effects (font (size 1.27 1.27))))
        )
      )
    )
	(symbol "antmicroResistors0402:R_243k_0402" (pin_numbers hide) (pin_names hide) (in_bom yes) (on_board yes)
      (property "Reference" "R" (at 20.32 -5.08 0)
        (effects (font (size 1.27 1.27) (thickness 0.15)) (justify left bottom))
      )
      (property "Value" "R_243k_0402" (at 20.32 -12.7 0)
        (effects (font (size 1.27 1.27) (thickness 0.15)) (justify left bottom) hide)
      )
      (property "Footprint" "antmicro-footprints:R_0402_1005Metric" (at 20.32 -15.24 0)
        (effects (font (size 1.27 1.27) (thickness 0.15)) (justify left bottom) hide)
      )
      (property "Datasheet" "https://www.bourns.com/docs/product-datasheets/cr.pdf" (at 20.32 -17.78 0)
        (effects (font (size 1.27 1.27) (thickness 0.15)) (justify left bottom) hide)
      )
      (property "MPN" "CR0402-FX-2433GLF" (at 20.32 -20.32 0)
        (effects (font (size 1.27 1.27) (thickness 0.15)) (justify left bottom) hide)
      )
      (property "Manufacturer" "Bourns" (at 20.32 -22.86 0)
        (effects (font (size 1.27 1.27) (thickness 0.15)) (justify left bottom) hide)
      )
      (property "License" "Apache-2.0" (at 20.32 -25.4 0)
        (effects (font (size 1.27 1.27) (thickness 0.15)) (justify left bottom) hide)
      )
      (property "Author" "Antmicro" (at 20.32 -27.94 0)
        (effects (font (size 1.27 1.27) (thickness 0.15)) (justify left bottom) hide)
      )
      (property "Val" "243k" (at 20.32 -7.62 0)
        (effects (font (size 1.27 1.27) (thickness 0.15)) (justify left bottom))
      )
      (property "Tolerance" "1%" (at 20.32 -10.16 0)
        (effects (font (size 1.27 1.27)) (justify left bottom) hide)
      )
      (property "ki_keywords" "0402, SMT, RESISTOR, PASSIVE" (at 0 0 0)
        (effects (font (size 1.27 1.27)) hide)
      )
      (property "ki_description" "SMD Chip Resistor" (at 0 0 0)
        (effects (font (size 1.27 1.27)) hide)
      )
      (symbol "R_243k_0402_0_1"
        (rectangle (start 0.635 0.889) (end 4.445 -0.889)
          (stroke (width 0.254) (type default))
          (fill (type none))
        )
      )
      (symbol "R_243k_0402_1_1"
        (pin passive line (at 0 0 0) (length 0.635)
          (name "~" (effects (font (size 1.27 1.27))))
          (number "1" (effects (font (size 1.27 1.27))))
        )
        (pin passive line (at 5.08 0 180) (length 0.635)
          (name "~" (effects (font (size 1.27 1.27))))
          (number "2" (effects (font (size 1.27 1.27))))
        )
      )
    )
	(symbol "antmicroResistors0402:R_2k2_0402" (pin_numbers hide) (pin_names hide) (in_bom yes) (on_board yes)
      (property "Reference" "R" (at 20.32 -5.08 0)
        (effects (font (size 1.27 1.27) (thickness 0.15)) (justify left bottom))
      )
      (property "Value" "R_2k2_0402" (at 20.32 -12.7 0)
        (effects (font (size 1.27 1.27) (thickness 0.15)) (justify left bottom) hide)
      )
      (property "Footprint" "antmicro-footprints:R_0402_1005Metric" (at 20.32 -15.24 0)
        (effects (font (size 1.27 1.27) (thickness 0.15)) (justify left bottom) hide)
      )
      (property "Datasheet" "https://www.bourns.com/docs/product-datasheets/cr.pdf" (at 20.32 -17.78 0)
        (effects (font (size 1.27 1.27) (thickness 0.15)) (justify left bottom) hide)
      )
      (property "MPN" "CR0402-FX-2201GLF" (at 20.32 -20.32 0)
        (effects (font (size 1.27 1.27) (thickness 0.15)) (justify left bottom) hide)
      )
      (property "Manufacturer" "Bourns" (at 20.32 -22.86 0)
        (effects (font (size 1.27 1.27) (thickness 0.15)) (justify left bottom) hide)
      )
      (property "License" "Apache-2.0" (at 20.32 -25.4 0)
        (effects (font (size 1.27 1.27) (thickness 0.15)) (justify left bottom) hide)
      )
      (property "Author" "Antmicro" (at 20.32 -27.94 0)
        (effects (font (size 1.27 1.27) (thickness 0.15)) (justify left bottom) hide)
      )
      (property "Val" "2k2" (at 20.32 -7.62 0)
        (effects (font (size 1.27 1.27) (thickness 0.15)) (justify left bottom))
      )
      (property "Tolerance" "1%" (at 20.32 -10.16 0)
        (effects (font (size 1.27 1.27)) (justify left bottom) hide)
      )
      (property "ki_keywords" "0402, SMT, RESISTOR, PASSIVE" (at 0 0 0)
        (effects (font (size 1.27 1.27)) hide)
      )
      (property "ki_description" "SMD Chip Resistor, 2.2 kohm, ± 1%, 62.5 mW, 0402 [1005 Metric], Thick Film, General Purpose" (at 0 0 0)
        (effects (font (size 1.27 1.27)) hide)
      )
      (symbol "R_2k2_0402_0_1"
        (rectangle (start 0.635 0.889) (end 4.445 -0.889)
          (stroke (width 0.254) (type default))
          (fill (type none))
        )
      )
      (symbol "R_2k2_0402_1_1"
        (pin passive line (at 0 0 0) (length 0.635)
          (name "~" (effects (font (size 1.27 1.27))))
          (number "1" (effects (font (size 1.27 1.27))))
        )
        (pin passive line (at 5.08 0 180) (length 0.635)
          (name "~" (effects (font (size 1.27 1.27))))
          (number "2" (effects (font (size 1.27 1.27))))
        )
      )
    )
	(symbol "antmicroResistors0402:R_316k_0402" (pin_numbers hide) (pin_names hide) (in_bom yes) (on_board yes)
      (property "Reference" "R" (at 20.32 -5.08 0)
        (effects (font (size 1.27 1.27) (thickness 0.15)) (justify left bottom))
      )
      (property "Value" "R_316k_0402" (at 20.32 -12.7 0)
        (effects (font (size 1.27 1.27) (thickness 0.15)) (justify left bottom) hide)
      )
      (property "Footprint" "antmicro-footprints:R_0402_1005Metric" (at 20.32 -15.24 0)
        (effects (font (size 1.27 1.27) (thickness 0.15)) (justify left bottom) hide)
      )
      (property "Datasheet" "https://www.bourns.com/docs/product-datasheets/cr.pdf" (at 20.32 -17.78 0)
        (effects (font (size 1.27 1.27) (thickness 0.15)) (justify left bottom) hide)
      )
      (property "MPN" "CR0402-FX-3163GLF" (at 20.32 -20.32 0)
        (effects (font (size 1.27 1.27) (thickness 0.15)) (justify left bottom) hide)
      )
      (property "Manufacturer" "Bourns" (at 20.32 -22.86 0)
        (effects (font (size 1.27 1.27) (thickness 0.15)) (justify left bottom) hide)
      )
      (property "License" "Apache-2.0" (at 20.32 -25.4 0)
        (effects (font (size 1.27 1.27) (thickness 0.15)) (justify left bottom) hide)
      )
      (property "Author" "Antmicro" (at 20.32 -27.94 0)
        (effects (font (size 1.27 1.27) (thickness 0.15)) (justify left bottom) hide)
      )
      (property "Val" "316k" (at 20.32 -7.62 0)
        (effects (font (size 1.27 1.27) (thickness 0.15)) (justify left bottom))
      )
      (property "Tolerance" "1%" (at 20.32 -10.16 0)
        (effects (font (size 1.27 1.27)) (justify left bottom) hide)
      )
      (property "ki_keywords" "0402, SMT, RESISTOR, PASSIVE" (at 0 0 0)
        (effects (font (size 1.27 1.27)) hide)
      )
      (property "ki_description" "SMD Chip Resistor" (at 0 0 0)
        (effects (font (size 1.27 1.27)) hide)
      )
      (symbol "R_316k_0402_0_1"
        (rectangle (start 0.635 0.889) (end 4.445 -0.889)
          (stroke (width 0.254) (type default))
          (fill (type none))
        )
      )
      (symbol "R_316k_0402_1_1"
        (pin passive line (at 0 0 0) (length 0.635)
          (name "~" (effects (font (size 1.27 1.27))))
          (number "1" (effects (font (size 1.27 1.27))))
        )
        (pin passive line (at 5.08 0 180) (length 0.635)
          (name "~" (effects (font (size 1.27 1.27))))
          (number "2" (effects (font (size 1.27 1.27))))
        )
      )
    )
	(symbol "antmicroResistors0402:R_330R_0402" (pin_numbers hide) (pin_names hide) (in_bom yes) (on_board yes)
      (property "Reference" "R" (at 20.32 -5.08 0)
        (effects (font (size 1.27 1.27) (thickness 0.15)) (justify left bottom))
      )
      (property "Value" "R_330R_0402" (at 20.32 -12.7 0)
        (effects (font (size 1.27 1.27) (thickness 0.15)) (justify left bottom) hide)
      )
      (property "Footprint" "antmicro-footprints:R_0402_1005Metric" (at 20.32 -15.24 0)
        (effects (font (size 1.27 1.27) (thickness 0.15)) (justify left bottom) hide)
      )
      (property "Datasheet" "https://www.bourns.com/docs/product-datasheets/cr.pdf" (at 20.32 -17.78 0)
        (effects (font (size 1.27 1.27) (thickness 0.15)) (justify left bottom) hide)
      )
      (property "MPN" "CR0402-FX-3300GLF" (at 20.32 -20.32 0)
        (effects (font (size 1.27 1.27) (thickness 0.15)) (justify left bottom) hide)
      )
      (property "Manufacturer" "Bourns" (at 20.32 -22.86 0)
        (effects (font (size 1.27 1.27) (thickness 0.15)) (justify left bottom) hide)
      )
      (property "License" "Apache-2.0" (at 20.32 -25.4 0)
        (effects (font (size 1.27 1.27) (thickness 0.15)) (justify left bottom) hide)
      )
      (property "Author" "Antmicro" (at 20.32 -27.94 0)
        (effects (font (size 1.27 1.27) (thickness 0.15)) (justify left bottom) hide)
      )
      (property "Val" "330R" (at 20.32 -7.62 0)
        (effects (font (size 1.27 1.27) (thickness 0.15)) (justify left bottom))
      )
      (property "Tolerance" "1%" (at 20.32 -10.16 0)
        (effects (font (size 1.27 1.27)) (justify left bottom) hide)
      )
      (property "ki_keywords" "0402, SMT, RESISTOR, PASSIVE" (at 0 0 0)
        (effects (font (size 1.27 1.27)) hide)
      )
      (property "ki_description" "SMD Chip Resistor, 330 ohm, ± 1%, 62.5 mW, 0402 [1005 Metric], Thick Film, General Purpose" (at 0 0 0)
        (effects (font (size 1.27 1.27)) hide)
      )
      (symbol "R_330R_0402_0_1"
        (rectangle (start 0.635 0.889) (end 4.445 -0.889)
          (stroke (width 0.254) (type default))
          (fill (type none))
        )
      )
      (symbol "R_330R_0402_1_1"
        (pin passive line (at 0 0 0) (length 0.635)
          (name "~" (effects (font (size 1.27 1.27))))
          (number "1" (effects (font (size 1.27 1.27))))
        )
        (pin passive line (at 5.08 0 180) (length 0.635)
          (name "~" (effects (font (size 1.27 1.27))))
          (number "2" (effects (font (size 1.27 1.27))))
        )
      )
    )
	(symbol "antmicroResistors0402:R_357k_0402" (pin_numbers hide) (pin_names hide) (in_bom yes) (on_board yes)
      (property "Reference" "R" (at 20.32 -5.08 0)
        (effects (font (size 1.27 1.27) (thickness 0.15)) (justify left bottom))
      )
      (property "Value" "R_357k_0402" (at 20.32 -12.7 0)
        (effects (font (size 1.27 1.27) (thickness 0.15)) (justify left bottom) hide)
      )
      (property "Footprint" "antmicro-footprints:R_0402_1005Metric" (at 20.32 -15.24 0)
        (effects (font (size 1.27 1.27) (thickness 0.15)) (justify left bottom) hide)
      )
      (property "Datasheet" "https://www.bourns.com/docs/product-datasheets/cr.pdf" (at 20.32 -17.78 0)
        (effects (font (size 1.27 1.27) (thickness 0.15)) (justify left bottom) hide)
      )
      (property "MPN" "CR0402-FX-3573GLF" (at 20.32 -20.32 0)
        (effects (font (size 1.27 1.27) (thickness 0.15)) (justify left bottom) hide)
      )
      (property "Manufacturer" "Bourns" (at 20.32 -22.86 0)
        (effects (font (size 1.27 1.27) (thickness 0.15)) (justify left bottom) hide)
      )
      (property "License" "Apache-2.0" (at 20.32 -25.4 0)
        (effects (font (size 1.27 1.27) (thickness 0.15)) (justify left bottom) hide)
      )
      (property "Author" "Antmicro" (at 20.32 -27.94 0)
        (effects (font (size 1.27 1.27) (thickness 0.15)) (justify left bottom) hide)
      )
      (property "Val" "357k" (at 20.32 -7.62 0)
        (effects (font (size 1.27 1.27) (thickness 0.15)) (justify left bottom))
      )
      (property "Tolerance" "1%" (at 20.32 -10.16 0)
        (effects (font (size 1.27 1.27)) (justify left bottom) hide)
      )
      (property "ki_keywords" "0402, SMT, RESISTOR, PASSIVE" (at 0 0 0)
        (effects (font (size 1.27 1.27)) hide)
      )
      (property "ki_description" "SMD Chip Resistor" (at 0 0 0)
        (effects (font (size 1.27 1.27)) hide)
      )
      (symbol "R_357k_0402_0_1"
        (rectangle (start 0.635 0.889) (end 4.445 -0.889)
          (stroke (width 0.254) (type default))
          (fill (type none))
        )
      )
      (symbol "R_357k_0402_1_1"
        (pin passive line (at 0 0 0) (length 0.635)
          (name "~" (effects (font (size 1.27 1.27))))
          (number "1" (effects (font (size 1.27 1.27))))
        )
        (pin passive line (at 5.08 0 180) (length 0.635)
          (name "~" (effects (font (size 1.27 1.27))))
          (number "2" (effects (font (size 1.27 1.27))))
        )
      )
    )
	(symbol "antmicroResistors0402:R_453k_0402" (pin_numbers hide) (pin_names hide) (in_bom yes) (on_board yes)
      (property "Reference" "R" (at 20.32 -5.08 0)
        (effects (font (size 1.27 1.27) (thickness 0.15)) (justify left bottom))
      )
      (property "Value" "R_453k_0402" (at 20.32 -12.7 0)
        (effects (font (size 1.27 1.27) (thickness 0.15)) (justify left bottom) hide)
      )
      (property "Footprint" "antmicro-footprints:R_0402_1005Metric" (at 20.32 -15.24 0)
        (effects (font (size 1.27 1.27) (thickness 0.15)) (justify left bottom) hide)
      )
      (property "Datasheet" "https://www.bourns.com/docs/product-datasheets/cr.pdf" (at 20.32 -17.78 0)
        (effects (font (size 1.27 1.27) (thickness 0.15)) (justify left bottom) hide)
      )
      (property "MPN" "CR0402-FX-4533GLF" (at 20.32 -20.32 0)
        (effects (font (size 1.27 1.27) (thickness 0.15)) (justify left bottom) hide)
      )
      (property "Manufacturer" "Bourns" (at 20.32 -22.86 0)
        (effects (font (size 1.27 1.27) (thickness 0.15)) (justify left bottom) hide)
      )
      (property "License" "Apache-2.0" (at 20.32 -25.4 0)
        (effects (font (size 1.27 1.27) (thickness 0.15)) (justify left bottom) hide)
      )
      (property "Author" "Antmicro" (at 20.32 -27.94 0)
        (effects (font (size 1.27 1.27) (thickness 0.15)) (justify left bottom) hide)
      )
      (property "Val" "453k" (at 20.32 -7.62 0)
        (effects (font (size 1.27 1.27) (thickness 0.15)) (justify left bottom))
      )
      (property "Tolerance" "1%" (at 20.32 -10.16 0)
        (effects (font (size 1.27 1.27)) (justify left bottom) hide)
      )
      (property "ki_keywords" "0402, SMT, RESISTOR, PASSIVE" (at 0 0 0)
        (effects (font (size 1.27 1.27)) hide)
      )
      (property "ki_description" "SMD Chip Resistor" (at 0 0 0)
        (effects (font (size 1.27 1.27)) hide)
      )
      (symbol "R_453k_0402_0_1"
        (rectangle (start 0.635 0.889) (end 4.445 -0.889)
          (stroke (width 0.254) (type default))
          (fill (type none))
        )
      )
      (symbol "R_453k_0402_1_1"
        (pin passive line (at 0 0 0) (length 0.635)
          (name "~" (effects (font (size 1.27 1.27))))
          (number "1" (effects (font (size 1.27 1.27))))
        )
        (pin passive line (at 5.08 0 180) (length 0.635)
          (name "~" (effects (font (size 1.27 1.27))))
          (number "2" (effects (font (size 1.27 1.27))))
        )
      )
    )
	(symbol "antmicroResistors0402:R_470k_0402" (pin_numbers hide) (pin_names hide) (in_bom yes) (on_board yes)
      (property "Reference" "R" (at 20.32 -5.08 0)
        (effects (font (size 1.27 1.27) (thickness 0.15)) (justify left bottom))
      )
      (property "Value" "R_470k_0402" (at 20.32 -12.7 0)
        (effects (font (size 1.27 1.27) (thickness 0.15)) (justify left bottom) hide)
      )
      (property "Footprint" "antmicro-footprints:R_0402_1005Metric" (at 20.32 -15.24 0)
        (effects (font (size 1.27 1.27) (thickness 0.15)) (justify left bottom) hide)
      )
      (property "Datasheet" "https://www.bourns.com/docs/product-datasheets/cr.pdf" (at 20.32 -17.78 0)
        (effects (font (size 1.27 1.27) (thickness 0.15)) (justify left bottom) hide)
      )
      (property "MPN" "CR0402-FX-4703GLF" (at 20.32 -20.32 0)
        (effects (font (size 1.27 1.27) (thickness 0.15)) (justify left bottom) hide)
      )
      (property "Manufacturer" "Bourns" (at 20.32 -22.86 0)
        (effects (font (size 1.27 1.27) (thickness 0.15)) (justify left bottom) hide)
      )
      (property "License" "Apache-2.0" (at 20.32 -25.4 0)
        (effects (font (size 1.27 1.27) (thickness 0.15)) (justify left bottom) hide)
      )
      (property "Author" "Antmicro" (at 20.32 -27.94 0)
        (effects (font (size 1.27 1.27) (thickness 0.15)) (justify left bottom) hide)
      )
      (property "Val" "470k" (at 20.32 -7.62 0)
        (effects (font (size 1.27 1.27) (thickness 0.15)) (justify left bottom))
      )
      (property "Tolerance" "1%" (at 20.32 -10.16 0)
        (effects (font (size 1.27 1.27)) (justify left bottom) hide)
      )
      (property "ki_keywords" "0402, SMT, RESISTOR, PASSIVE" (at 0 0 0)
        (effects (font (size 1.27 1.27)) hide)
      )
      (property "ki_description" "SMD Chip Resistor, 470 kohm, ± 1%, 62.5 mW, 0402 [1005 Metric], Thick Film, Sulfur Resistant" (at 0 0 0)
        (effects (font (size 1.27 1.27)) hide)
      )
      (symbol "R_470k_0402_0_1"
        (rectangle (start 0.635 0.889) (end 4.445 -0.889)
          (stroke (width 0.254) (type default))
          (fill (type none))
        )
      )
      (symbol "R_470k_0402_1_1"
        (pin passive line (at 0 0 0) (length 0.635)
          (name "~" (effects (font (size 1.27 1.27))))
          (number "1" (effects (font (size 1.27 1.27))))
        )
        (pin passive line (at 5.08 0 180) (length 0.635)
          (name "~" (effects (font (size 1.27 1.27))))
          (number "2" (effects (font (size 1.27 1.27))))
        )
      )
    )
	(symbol "antmicroResistors0402:R_47k_0402" (pin_numbers hide) (pin_names hide) (in_bom yes) (on_board yes)
      (property "Reference" "R" (at 20.32 -5.08 0)
        (effects (font (size 1.27 1.27) (thickness 0.15)) (justify left bottom))
      )
      (property "Value" "R_47k_0402" (at 20.32 -12.7 0)
        (effects (font (size 1.27 1.27) (thickness 0.15)) (justify left bottom) hide)
      )
      (property "Footprint" "antmicro-footprints:R_0402_1005Metric" (at 20.32 -15.24 0)
        (effects (font (size 1.27 1.27) (thickness 0.15)) (justify left bottom) hide)
      )
      (property "Datasheet" "https://www.bourns.com/docs/product-datasheets/cr.pdf" (at 20.32 -17.78 0)
        (effects (font (size 1.27 1.27) (thickness 0.15)) (justify left bottom) hide)
      )
      (property "MPN" "CR0402-FX-4702GLF" (at 20.32 -20.32 0)
        (effects (font (size 1.27 1.27) (thickness 0.15)) (justify left bottom) hide)
      )
      (property "Manufacturer" "Bourns" (at 20.32 -22.86 0)
        (effects (font (size 1.27 1.27) (thickness 0.15)) (justify left bottom) hide)
      )
      (property "License" "Apache-2.0" (at 20.32 -25.4 0)
        (effects (font (size 1.27 1.27) (thickness 0.15)) (justify left bottom) hide)
      )
      (property "Author" "Antmicro" (at 20.32 -27.94 0)
        (effects (font (size 1.27 1.27) (thickness 0.15)) (justify left bottom) hide)
      )
      (property "Val" "47k" (at 20.32 -7.62 0)
        (effects (font (size 1.27 1.27) (thickness 0.15)) (justify left bottom))
      )
      (property "Tolerance" "1%" (at 20.32 -10.16 0)
        (effects (font (size 1.27 1.27)) (justify left bottom) hide)
      )
      (property "ki_keywords" "0402, SMT, RESISTOR, PASSIVE" (at 0 0 0)
        (effects (font (size 1.27 1.27)) hide)
      )
      (property "ki_description" "SMD Chip Resistor, 47 kohm, ± 1%, 62.5 mW, 0402 [1005 Metric], Thick Film, General Purpose" (at 0 0 0)
        (effects (font (size 1.27 1.27)) hide)
      )
      (symbol "R_47k_0402_0_1"
        (rectangle (start 0.635 0.889) (end 4.445 -0.889)
          (stroke (width 0.254) (type default))
          (fill (type none))
        )
      )
      (symbol "R_47k_0402_1_1"
        (pin passive line (at 0 0 0) (length 0.635)
          (name "~" (effects (font (size 1.27 1.27))))
          (number "1" (effects (font (size 1.27 1.27))))
        )
        (pin passive line (at 5.08 0 180) (length 0.635)
          (name "~" (effects (font (size 1.27 1.27))))
          (number "2" (effects (font (size 1.27 1.27))))
        )
      )
    )
	(symbol "antmicroResistors0402:R_49R9_0402" (pin_numbers hide) (pin_names hide) (in_bom yes) (on_board yes)
      (property "Reference" "R" (at 20.32 -5.08 0)
        (effects (font (size 1.27 1.27) (thickness 0.15)) (justify left bottom))
      )
      (property "Value" "R_49R9_0402" (at 20.32 -12.7 0)
        (effects (font (size 1.27 1.27) (thickness 0.15)) (justify left bottom) hide)
      )
      (property "Footprint" "antmicro-footprints:R_0402_1005Metric" (at 20.32 -15.24 0)
        (effects (font (size 1.27 1.27) (thickness 0.15)) (justify left bottom) hide)
      )
      (property "Datasheet" "https://www.bourns.com/docs/product-datasheets/cr.pdf" (at 20.32 -17.78 0)
        (effects (font (size 1.27 1.27) (thickness 0.15)) (justify left bottom) hide)
      )
      (property "MPN" "CR0402-FX-49R9GLF" (at 20.32 -20.32 0)
        (effects (font (size 1.27 1.27) (thickness 0.15)) (justify left bottom) hide)
      )
      (property "Manufacturer" "Bourns" (at 20.32 -22.86 0)
        (effects (font (size 1.27 1.27) (thickness 0.15)) (justify left bottom) hide)
      )
      (property "License" "Apache-2.0" (at 20.32 -25.4 0)
        (effects (font (size 1.27 1.27) (thickness 0.15)) (justify left bottom) hide)
      )
      (property "Author" "Antmicro" (at 20.32 -27.94 0)
        (effects (font (size 1.27 1.27) (thickness 0.15)) (justify left bottom) hide)
      )
      (property "Val" "49R9" (at 20.32 -7.62 0)
        (effects (font (size 1.27 1.27) (thickness 0.15)) (justify left bottom))
      )
      (property "Tolerance" "1%" (at 20.32 -10.16 0)
        (effects (font (size 1.27 1.27)) (justify left bottom) hide)
      )
      (property "ki_keywords" "0402, SMT, RESISTOR, PASSIVE" (at 0 0 0)
        (effects (font (size 1.27 1.27)) hide)
      )
      (property "ki_description" "SMD Chip Resistor, 49.9 ohm, ± 1%, 62.5 mW, 0402 [1005 Metric], Thick Film, General Purpose" (at 0 0 0)
        (effects (font (size 1.27 1.27)) hide)
      )
      (symbol "R_49R9_0402_0_1"
        (rectangle (start 0.635 0.889) (end 4.445 -0.889)
          (stroke (width 0.254) (type default))
          (fill (type none))
        )
      )
      (symbol "R_49R9_0402_1_1"
        (pin passive line (at 0 0 0) (length 0.635)
          (name "~" (effects (font (size 1.27 1.27))))
          (number "1" (effects (font (size 1.27 1.27))))
        )
        (pin passive line (at 5.08 0 180) (length 0.635)
          (name "~" (effects (font (size 1.27 1.27))))
          (number "2" (effects (font (size 1.27 1.27))))
        )
      )
    )
	(symbol "antmicroResistors0402:R_4k7_0402" (pin_numbers hide) (pin_names hide) (in_bom yes) (on_board yes)
      (property "Reference" "R" (at 20.32 -5.08 0)
        (effects (font (size 1.27 1.27) (thickness 0.15)) (justify left bottom))
      )
      (property "Value" "R_4k7_0402" (at 20.32 -12.7 0)
        (effects (font (size 1.27 1.27) (thickness 0.15)) (justify left bottom) hide)
      )
      (property "Footprint" "antmicro-footprints:R_0402_1005Metric" (at 20.32 -15.24 0)
        (effects (font (size 1.27 1.27) (thickness 0.15)) (justify left bottom) hide)
      )
      (property "Datasheet" "https://www.bourns.com/docs/product-datasheets/cr.pdf" (at 20.32 -17.78 0)
        (effects (font (size 1.27 1.27) (thickness 0.15)) (justify left bottom) hide)
      )
      (property "MPN" "CR0402-FX-4701GLF" (at 20.32 -20.32 0)
        (effects (font (size 1.27 1.27) (thickness 0.15)) (justify left bottom) hide)
      )
      (property "Manufacturer" "Bourns" (at 20.32 -22.86 0)
        (effects (font (size 1.27 1.27) (thickness 0.15)) (justify left bottom) hide)
      )
      (property "License" "Apache-2.0" (at 20.32 -25.4 0)
        (effects (font (size 1.27 1.27) (thickness 0.15)) (justify left bottom) hide)
      )
      (property "Author" "Antmicro" (at 20.32 -27.94 0)
        (effects (font (size 1.27 1.27) (thickness 0.15)) (justify left bottom) hide)
      )
      (property "Val" "4k7" (at 20.32 -7.62 0)
        (effects (font (size 1.27 1.27) (thickness 0.15)) (justify left bottom))
      )
      (property "Tolerance" "1%" (at 20.32 -10.16 0)
        (effects (font (size 1.27 1.27)) (justify left bottom) hide)
      )
      (property "ki_keywords" "0402, SMT, RESISTOR, PASSIVE" (at 0 0 0)
        (effects (font (size 1.27 1.27)) hide)
      )
      (property "ki_description" "SMD Chip Resistor, 4.7 kohm, ± 1%, 62.5 mW, 0402 [1005 Metric], Thick Film, General Purpose" (at 0 0 0)
        (effects (font (size 1.27 1.27)) hide)
      )
      (symbol "R_4k7_0402_0_1"
        (rectangle (start 0.635 0.889) (end 4.445 -0.889)
          (stroke (width 0.254) (type default))
          (fill (type none))
        )
      )
      (symbol "R_4k7_0402_1_1"
        (pin passive line (at 0 0 0) (length 0.635)
          (name "~" (effects (font (size 1.27 1.27))))
          (number "1" (effects (font (size 1.27 1.27))))
        )
        (pin passive line (at 5.08 0 180) (length 0.635)
          (name "~" (effects (font (size 1.27 1.27))))
          (number "2" (effects (font (size 1.27 1.27))))
        )
      )
    )
	(symbol "antmicroResistors0402:R_51R_0402" (pin_numbers hide) (pin_names hide) (in_bom yes) (on_board yes)
      (property "Reference" "R" (at 20.32 -5.08 0)
        (effects (font (size 1.27 1.27) (thickness 0.15)) (justify left bottom))
      )
      (property "Value" "R_51R_0402" (at 20.32 -12.7 0)
        (effects (font (size 1.27 1.27) (thickness 0.15)) (justify left bottom) hide)
      )
      (property "Footprint" "antmicro-footprints:R_0402_1005Metric" (at 20.32 -15.24 0)
        (effects (font (size 1.27 1.27) (thickness 0.15)) (justify left bottom) hide)
      )
      (property "Datasheet" "https://www.bourns.com/docs/product-datasheets/cr.pdf" (at 20.32 -17.78 0)
        (effects (font (size 1.27 1.27) (thickness 0.15)) (justify left bottom) hide)
      )
      (property "MPN" "CR0402-FX-51R0GLF" (at 20.32 -20.32 0)
        (effects (font (size 1.27 1.27) (thickness 0.15)) (justify left bottom) hide)
      )
      (property "Manufacturer" "Bourns" (at 20.32 -22.86 0)
        (effects (font (size 1.27 1.27) (thickness 0.15)) (justify left bottom) hide)
      )
      (property "License" "Apache-2.0" (at 20.32 -25.4 0)
        (effects (font (size 1.27 1.27) (thickness 0.15)) (justify left bottom) hide)
      )
      (property "Author" "Antmicro" (at 20.32 -27.94 0)
        (effects (font (size 1.27 1.27) (thickness 0.15)) (justify left bottom) hide)
      )
      (property "Val" "51R" (at 20.32 -7.62 0)
        (effects (font (size 1.27 1.27) (thickness 0.15)) (justify left bottom))
      )
      (property "Tolerance" "1%" (at 20.32 -10.16 0)
        (effects (font (size 1.27 1.27)) (justify left bottom) hide)
      )
      (property "ki_keywords" "0402, SMT, RESISTOR, PASSIVE" (at 0 0 0)
        (effects (font (size 1.27 1.27)) hide)
      )
      (property "ki_description" "SMD Chip Resistor, 51 ohm, ± 1%, 63 mW, 0402 [1005 Metric], Thick Film, General Purpose" (at 0 0 0)
        (effects (font (size 1.27 1.27)) hide)
      )
      (symbol "R_51R_0402_0_1"
        (rectangle (start 0.635 0.889) (end 4.445 -0.889)
          (stroke (width 0.254) (type default))
          (fill (type none))
        )
      )
      (symbol "R_51R_0402_1_1"
        (pin passive line (at 0 0 0) (length 0.635)
          (name "~" (effects (font (size 1.27 1.27))))
          (number "1" (effects (font (size 1.27 1.27))))
        )
        (pin passive line (at 5.08 0 180) (length 0.635)
          (name "~" (effects (font (size 1.27 1.27))))
          (number "2" (effects (font (size 1.27 1.27))))
        )
      )
    )
	(symbol "antmicroResistors0402:R_53k6_0402" (pin_numbers hide) (pin_names hide) (in_bom yes) (on_board yes)
      (property "Reference" "R" (at 20.32 -5.08 0)
        (effects (font (size 1.27 1.27) (thickness 0.15)) (justify left bottom))
      )
      (property "Value" "R_53k6_0402" (at 20.32 -12.7 0)
        (effects (font (size 1.27 1.27) (thickness 0.15)) (justify left bottom) hide)
      )
      (property "Footprint" "antmicro-footprints:R_0402_1005Metric" (at 20.32 -15.24 0)
        (effects (font (size 1.27 1.27) (thickness 0.15)) (justify left bottom) hide)
      )
      (property "Datasheet" "https://www.bourns.com/docs/product-datasheets/cr.pdf" (at 20.32 -17.78 0)
        (effects (font (size 1.27 1.27) (thickness 0.15)) (justify left bottom) hide)
      )
      (property "MPN" "CR0402-FX-5362GLF" (at 20.32 -20.32 0)
        (effects (font (size 1.27 1.27) (thickness 0.15)) (justify left bottom) hide)
      )
      (property "Manufacturer" "Bourns" (at 20.32 -22.86 0)
        (effects (font (size 1.27 1.27) (thickness 0.15)) (justify left bottom) hide)
      )
      (property "License" "Apache-2.0" (at 20.32 -25.4 0)
        (effects (font (size 1.27 1.27) (thickness 0.15)) (justify left bottom) hide)
      )
      (property "Author" "Antmicro" (at 20.32 -27.94 0)
        (effects (font (size 1.27 1.27) (thickness 0.15)) (justify left bottom) hide)
      )
      (property "Val" "53k6" (at 20.32 -7.62 0)
        (effects (font (size 1.27 1.27) (thickness 0.15)) (justify left bottom))
      )
      (property "Tolerance" "1%" (at 20.32 -10.16 0)
        (effects (font (size 1.27 1.27)) (justify left bottom) hide)
      )
      (property "ki_keywords" "0402, SMT, RESISTOR, PASSIVE" (at 0 0 0)
        (effects (font (size 1.27 1.27)) hide)
      )
      (property "ki_description" "SMD Chip Resistor" (at 0 0 0)
        (effects (font (size 1.27 1.27)) hide)
      )
      (symbol "R_53k6_0402_0_1"
        (rectangle (start 0.635 0.889) (end 4.445 -0.889)
          (stroke (width 0.254) (type default))
          (fill (type none))
        )
      )
      (symbol "R_53k6_0402_1_1"
        (pin passive line (at 0 0 0) (length 0.635)
          (name "~" (effects (font (size 1.27 1.27))))
          (number "1" (effects (font (size 1.27 1.27))))
        )
        (pin passive line (at 5.08 0 180) (length 0.635)
          (name "~" (effects (font (size 1.27 1.27))))
          (number "2" (effects (font (size 1.27 1.27))))
        )
      )
    )
	(symbol "antmicroResistors0402:R_66k5_0402" (pin_numbers hide) (pin_names hide) (in_bom yes) (on_board yes)
      (property "Reference" "R" (at 20.32 -5.08 0)
        (effects (font (size 1.27 1.27) (thickness 0.15)) (justify left bottom))
      )
      (property "Value" "R_66k5_0402" (at 20.32 -12.7 0)
        (effects (font (size 1.27 1.27) (thickness 0.15)) (justify left bottom) hide)
      )
      (property "Footprint" "antmicro-footprints:R_0402_1005Metric" (at 20.32 -15.24 0)
        (effects (font (size 1.27 1.27) (thickness 0.15)) (justify left bottom) hide)
      )
      (property "Datasheet" "https://www.bourns.com/docs/product-datasheets/cr.pdf" (at 20.32 -17.78 0)
        (effects (font (size 1.27 1.27) (thickness 0.15)) (justify left bottom) hide)
      )
      (property "MPN" "CR0402-FX-6652GLF" (at 20.32 -20.32 0)
        (effects (font (size 1.27 1.27) (thickness 0.15)) (justify left bottom) hide)
      )
      (property "Manufacturer" "Bourns" (at 20.32 -22.86 0)
        (effects (font (size 1.27 1.27) (thickness 0.15)) (justify left bottom) hide)
      )
      (property "License" "Apache-2.0" (at 20.32 -25.4 0)
        (effects (font (size 1.27 1.27) (thickness 0.15)) (justify left bottom) hide)
      )
      (property "Author" "Antmicro" (at 20.32 -27.94 0)
        (effects (font (size 1.27 1.27) (thickness 0.15)) (justify left bottom) hide)
      )
      (property "Val" "66k5" (at 20.32 -7.62 0)
        (effects (font (size 1.27 1.27) (thickness 0.15)) (justify left bottom))
      )
      (property "Tolerance" "1%" (at 20.32 -10.16 0)
        (effects (font (size 1.27 1.27)) (justify left bottom) hide)
      )
      (property "ki_keywords" "0402, SMT, RESISTOR, PASSIVE" (at 0 0 0)
        (effects (font (size 1.27 1.27)) hide)
      )
      (property "ki_description" "SMD Chip Resistor" (at 0 0 0)
        (effects (font (size 1.27 1.27)) hide)
      )
      (symbol "R_66k5_0402_0_1"
        (rectangle (start 0.635 0.889) (end 4.445 -0.889)
          (stroke (width 0.254) (type default))
          (fill (type none))
        )
      )
      (symbol "R_66k5_0402_1_1"
        (pin passive line (at 0 0 0) (length 0.635)
          (name "~" (effects (font (size 1.27 1.27))))
          (number "1" (effects (font (size 1.27 1.27))))
        )
        (pin passive line (at 5.08 0 180) (length 0.635)
          (name "~" (effects (font (size 1.27 1.27))))
          (number "2" (effects (font (size 1.27 1.27))))
        )
      )
    )
	(symbol "antmicroResistors0603:R_0R_0603" (pin_numbers hide) (pin_names hide) (in_bom yes) (on_board yes)
      (property "Reference" "R" (at 20.32 -5.08 0)
        (effects (font (size 1.27 1.27) (thickness 0.15)) (justify left bottom))
      )
      (property "Value" "R_0R_0603" (at 20.32 -12.7 0)
        (effects (font (size 1.27 1.27) (thickness 0.15)) (justify left bottom) hide)
      )
      (property "Footprint" "antmicro-footprints:R_0603_1608Metric" (at 20.32 -15.24 0)
        (effects (font (size 1.27 1.27) (thickness 0.15)) (justify left bottom) hide)
      )
      (property "Datasheet" "https://www.bourns.com/docs/product-datasheets/cr.pdf?sfvrsn=574d41f6_14" (at 20.32 -17.78 0)
        (effects (font (size 1.27 1.27) (thickness 0.15)) (justify left bottom) hide)
      )
      (property "MPN" "CR0603-J/-000ELF" (at 20.32 -20.32 0)
        (effects (font (size 1.27 1.27) (thickness 0.15)) (justify left bottom) hide)
      )
      (property "Manufacturer" "Bourns" (at 20.32 -22.86 0)
        (effects (font (size 1.27 1.27) (thickness 0.15)) (justify left bottom) hide)
      )
      (property "License" "Apache-2.0" (at 20.32 -25.4 0)
        (effects (font (size 1.27 1.27) (thickness 0.15)) (justify left bottom) hide)
      )
      (property "Author" "Antmicro" (at 20.32 -27.94 0)
        (effects (font (size 1.27 1.27) (thickness 0.15)) (justify left bottom) hide)
      )
      (property "Val" "0R" (at 20.32 -7.62 0)
        (effects (font (size 1.27 1.27) (thickness 0.15)) (justify left bottom))
      )
      (property "Tolerance" "~" (at 20.32 -10.16 0)
        (effects (font (size 1.27 1.27)) (justify left bottom) hide)
      )
      (property "Current" "1A" (at 20.32 -30.48 0)
        (effects (font (size 1.27 1.27) (thickness 0.15)) (justify left bottom) hide)
      )
      (property "ki_keywords" "0603, SMT, RESISTOR, PASSIVE" (at 0 0 0)
        (effects (font (size 1.27 1.27)) hide)
      )
      (property "ki_description" "Zero Ohm Resistor, Jumper, 0603 [1608 Metric], Thick Film, 100 mW, 1 A, Surface Mount Device, CR" (at 0 0 0)
        (effects (font (size 1.27 1.27)) hide)
      )
      (symbol "R_0R_0603_0_1"
        (rectangle (start 0.635 0.889) (end 4.445 -0.889)
          (stroke (width 0.254) (type default))
          (fill (type none))
        )
      )
      (symbol "R_0R_0603_1_1"
        (pin passive line (at 0 0 0) (length 0.635)
          (name "~" (effects (font (size 1.27 1.27))))
          (number "1" (effects (font (size 1.27 1.27))))
        )
        (pin passive line (at 5.08 0 180) (length 0.635)
          (name "~" (effects (font (size 1.27 1.27))))
          (number "2" (effects (font (size 1.27 1.27))))
        )
      )
    )
	(symbol "antmicroResistors0603:R_10R_0603" (pin_numbers hide) (pin_names hide) (in_bom yes) (on_board yes)
      (property "Reference" "R" (at 20.32 -5.08 0)
        (effects (font (size 1.27 1.27) (thickness 0.15)) (justify left bottom))
      )
      (property "Value" "R_10R_0603" (at 20.32 -12.7 0)
        (effects (font (size 1.27 1.27) (thickness 0.15)) (justify left bottom) hide)
      )
      (property "Footprint" "antmicro-footprints:R_0603_1608Metric" (at 20.32 -15.24 0)
        (effects (font (size 1.27 1.27) (thickness 0.15)) (justify left bottom) hide)
      )
      (property "Datasheet" "https://www.bourns.com/docs/product-datasheets/cr.pdf" (at 20.32 -17.78 0)
        (effects (font (size 1.27 1.27) (thickness 0.15)) (justify left bottom) hide)
      )
      (property "MPN" "CR0603-FX-10R0ELF" (at 20.32 -20.32 0)
        (effects (font (size 1.27 1.27) (thickness 0.15)) (justify left bottom) hide)
      )
      (property "Manufacturer" "Bourns" (at 20.32 -22.86 0)
        (effects (font (size 1.27 1.27) (thickness 0.15)) (justify left bottom) hide)
      )
      (property "License" "Apache-2.0" (at 20.32 -25.4 0)
        (effects (font (size 1.27 1.27) (thickness 0.15)) (justify left bottom) hide)
      )
      (property "Author" "Antmicro" (at 20.32 -27.94 0)
        (effects (font (size 1.27 1.27) (thickness 0.15)) (justify left bottom) hide)
      )
      (property "Val" "10R" (at 20.32 -7.62 0)
        (effects (font (size 1.27 1.27) (thickness 0.15)) (justify left bottom))
      )
      (property "Tolerance" "1%" (at 20.32 -10.16 0)
        (effects (font (size 1.27 1.27)) (justify left bottom) hide)
      )
      (property "ki_keywords" "0603, SMT, RESISTOR, PASSIVE" (at 0 0 0)
        (effects (font (size 1.27 1.27)) hide)
      )
      (property "ki_description" "SMD Chip Resistor, 10 ohm, ± 1%, 100 mW, 0603 [1608 Metric], Thick Film, General Purpose" (at 0 0 0)
        (effects (font (size 1.27 1.27)) hide)
      )
      (symbol "R_10R_0603_0_1"
        (rectangle (start 0.635 0.889) (end 4.445 -0.889)
          (stroke (width 0.254) (type default))
          (fill (type none))
        )
      )
      (symbol "R_10R_0603_1_1"
        (pin passive line (at 0 0 0) (length 0.635)
          (name "~" (effects (font (size 1.27 1.27))))
          (number "1" (effects (font (size 1.27 1.27))))
        )
        (pin passive line (at 5.08 0 180) (length 0.635)
          (name "~" (effects (font (size 1.27 1.27))))
          (number "2" (effects (font (size 1.27 1.27))))
        )
      )
    )
	(symbol "antmicroResistorsmisc:R_0R_1206" (pin_numbers hide) (pin_names hide) (in_bom yes) (on_board yes)
      (property "Reference" "R" (at 20.32 -5.08 0)
        (effects (font (size 1.27 1.27) (thickness 0.15)) (justify left bottom))
      )
      (property "Value" "R_0R_1206" (at 20.32 -12.7 0)
        (effects (font (size 1.27 1.27) (thickness 0.15)) (justify left bottom) hide)
      )
      (property "Footprint" "antmicro-footprints:R_1206_3216Metric" (at 20.32 -15.24 0)
        (effects (font (size 1.27 1.27) (thickness 0.15)) (justify left bottom) hide)
      )
      (property "Datasheet" "https://www.farnell.com/datasheets/2860635.pdf" (at 20.32 -17.78 0)
        (effects (font (size 1.27 1.27) (thickness 0.15)) (justify left bottom) hide)
      )
      (property "MPN" "MCMR12X000_PTL" (at 20.32 -20.32 0)
        (effects (font (size 1.27 1.27) (thickness 0.15)) (justify left bottom) hide)
      )
      (property "Manufacturer" "Multicomp Pro" (at 20.32 -22.86 0)
        (effects (font (size 1.27 1.27) (thickness 0.15)) (justify left bottom) hide)
      )
      (property "License" "Apache-2.0" (at 20.32 -25.4 0)
        (effects (font (size 1.27 1.27) (thickness 0.15)) (justify left bottom) hide)
      )
      (property "Author" "Antmicro" (at 20.32 -27.94 0)
        (effects (font (size 1.27 1.27) (thickness 0.15)) (justify left bottom) hide)
      )
      (property "Val" "0R" (at 20.32 -7.62 0)
        (effects (font (size 1.27 1.27) (thickness 0.15)) (justify left bottom))
      )
      (property "Tolerance" "~" (at 20.32 -10.16 0)
        (effects (font (size 1.27 1.27)) (justify left bottom) hide)
      )
      (property "Current" "2A" (at 20.32 -30.48 0)
        (effects (font (size 1.27 1.27) (thickness 0.15)) (justify left bottom) hide)
      )
      (property "ki_keywords" "1206, SMT, RESISTOR, PASSIVE" (at 0 0 0)
        (effects (font (size 1.27 1.27)) hide)
      )
      (property "ki_description" "Zero Ohm Resistor, Jumper, 1206 [3216 Metric], Thick Film, 250 mW, 2 A, Surface Mount Device" (at 0 0 0)
        (effects (font (size 1.27 1.27)) hide)
      )
      (symbol "R_0R_1206_0_1"
        (rectangle (start 0.635 0.889) (end 4.445 -0.889)
          (stroke (width 0.254) (type default))
          (fill (type none))
        )
      )
      (symbol "R_0R_1206_1_1"
        (pin passive line (at 0 0 0) (length 0.635)
          (name "~" (effects (font (size 1.27 1.27))))
          (number "1" (effects (font (size 1.27 1.27))))
        )
        (pin passive line (at 5.08 0 180) (length 0.635)
          (name "~" (effects (font (size 1.27 1.27))))
          (number "2" (effects (font (size 1.27 1.27))))
        )
      )
    )
	(symbol "antmicroTVSDiodes:SP3011-06UTG" (pin_names hide) (in_bom yes) (on_board yes)
      (property "Reference" "D" (at 13.97 -3.81 0)
        (effects (font (size 1.27 1.27) (thickness 0.15)) (justify left bottom))
      )
      (property "Value" "SP3011-06UTG" (at 13.97 -8.89 0)
        (effects (font (size 1.27 1.27) (thickness 0.15)) (justify left bottom) hide)
      )
      (property "Footprint" "antmicro-footprints:USON-14_3.5x1.35_P0.5mm" (at 13.97 -11.43 0)
        (effects (font (size 1.27 1.27) (thickness 0.15)) (justify left bottom) hide)
      )
      (property "Datasheet" "https://www.littelfuse.com/media?resourcetype=datasheets&itemid=c9002a97-9994-449b-b722-f45ab5538c7f&filename=littelfuse-tvs-diode-array-sp3011-datasheet" (at 13.97 -13.97 0)
        (effects (font (size 1.27 1.27) (thickness 0.15)) (justify left bottom) hide)
      )
      (property "MPN" "SP3011-06UTG" (at 13.97 -6.35 0)
        (effects (font (size 1.27 1.27) (thickness 0.15)) (justify left bottom))
      )
      (property "Manufacturer" "Littelfuse" (at 13.97 -16.51 0)
        (effects (font (size 1.27 1.27) (thickness 0.15)) (justify left bottom) hide)
      )
      (property "Author" "Antmicro" (at 13.97 -19.05 0)
        (effects (font (size 1.27 1.27) (thickness 0.15)) (justify left bottom) hide)
      )
      (property "License" "Apache-2.0" (at 13.97 -21.59 0)
        (effects (font (size 1.27 1.27) (thickness 0.15)) (justify left bottom) hide)
      )
      (property "ki_keywords" "SMT, DIODE, SEMICONDUCTOR, TVS, ESD" (at 0 0 0)
        (effects (font (size 1.27 1.27)) hide)
      )
      (property "ki_description" "TVS diode array, 8 kV, USON-14, 6 V, 0.4 pF" (at 0 0 0)
        (effects (font (size 1.27 1.27)) hide)
      )
      (symbol "SP3011-06UTG_0_0"
        (pin passive line (at 0 -5.08 0) (length 2.54)
          (name "~" (effects (font (size 1.27 1.27))))
          (number "11" (effects (font (size 1.27 1.27))))
        )
        (pin passive line (at 0 -7.62 0) (length 2.54)
          (name "~" (effects (font (size 1.27 1.27))))
          (number "12" (effects (font (size 1.27 1.27))))
        )
        (pin passive line (at 0 -10.16 0) (length 2.54)
          (name "~" (effects (font (size 1.27 1.27))))
          (number "13" (effects (font (size 1.27 1.27))))
        )
        (pin passive line (at 0 -12.7 0) (length 2.54)
          (name "~" (effects (font (size 1.27 1.27))))
          (number "14" (effects (font (size 1.27 1.27))))
        )
      )
      (symbol "SP3011-06UTG_1_1"
        (polyline
          (pts
            (xy 2.54 -12.7)
            (xy 7.62 -12.7)
          )
          (stroke (width 0.254) (type default))
          (fill (type background))
        )
        (polyline
          (pts
            (xy 2.54 -10.16)
            (xy 7.62 -10.16)
          )
          (stroke (width 0.254) (type default))
          (fill (type background))
        )
        (polyline
          (pts
            (xy 2.54 -7.62)
            (xy 7.62 -7.62)
          )
          (stroke (width 0.254) (type default))
          (fill (type background))
        )
        (polyline
          (pts
            (xy 2.54 -5.08)
            (xy 7.62 -5.08)
          )
          (stroke (width 0.254) (type default))
          (fill (type background))
        )
        (polyline
          (pts
            (xy 2.54 -2.54)
            (xy 7.62 -2.54)
          )
          (stroke (width 0.254) (type default))
          (fill (type background))
        )
        (polyline
          (pts
            (xy 2.54 0)
            (xy 7.62 0)
          )
          (stroke (width 0.254) (type default))
          (fill (type background))
        )
        (polyline
          (pts
            (xy 7.62 -15.24)
            (xy 2.54 -15.24)
          )
          (stroke (width 0.254) (type default))
          (fill (type background))
        )
        (polyline
          (pts
            (xy 7.62 0)
            (xy 7.62 -15.24)
          )
          (stroke (width 0.254) (type default))
          (fill (type background))
        )
        (polyline
          (pts
            (xy 4.826 -13.335)
            (xy 5.08 -13.081)
            (xy 5.08 -12.319)
            (xy 5.334 -12.065)
          )
          (stroke (width 0.254) (type default))
          (fill (type background))
        )
        (polyline
          (pts
            (xy 4.826 -10.795)
            (xy 5.08 -10.541)
            (xy 5.08 -9.779)
            (xy 5.334 -9.525)
          )
          (stroke (width 0.254) (type default))
          (fill (type background))
        )
        (polyline
          (pts
            (xy 4.826 -8.255)
            (xy 5.08 -8.001)
            (xy 5.08 -7.239)
            (xy 5.334 -6.985)
          )
          (stroke (width 0.254) (type default))
          (fill (type background))
        )
        (polyline
          (pts
            (xy 4.826 -5.715)
            (xy 5.08 -5.461)
            (xy 5.08 -4.699)
            (xy 5.334 -4.445)
          )
          (stroke (width 0.254) (type default))
          (fill (type background))
        )
        (polyline
          (pts
            (xy 4.826 -3.175)
            (xy 5.08 -2.921)
            (xy 5.08 -2.159)
            (xy 5.334 -1.905)
          )
          (stroke (width 0.254) (type default))
          (fill (type background))
        )
        (polyline
          (pts
            (xy 4.826 -0.635)
            (xy 5.08 -0.381)
            (xy 5.08 0.381)
            (xy 5.334 0.635)
          )
          (stroke (width 0.254) (type default))
          (fill (type background))
        )
        (polyline
          (pts
            (xy 5.08 -12.7)
            (xy 3.81 -13.335)
            (xy 3.81 -12.065)
            (xy 5.08 -12.7)
          )
          (stroke (width 0.254) (type default))
          (fill (type background))
        )
        (polyline
          (pts
            (xy 5.08 -10.16)
            (xy 3.81 -10.795)
            (xy 3.81 -9.525)
            (xy 5.08 -10.16)
          )
          (stroke (width 0.254) (type default))
          (fill (type background))
        )
        (polyline
          (pts
            (xy 5.08 -10.16)
            (xy 6.35 -9.525)
            (xy 6.35 -10.795)
            (xy 5.08 -10.16)
          )
          (stroke (width 0.254) (type default))
          (fill (type background))
        )
        (polyline
          (pts
            (xy 5.08 -7.62)
            (xy 3.81 -8.255)
            (xy 3.81 -6.985)
            (xy 5.08 -7.62)
          )
          (stroke (width 0.254) (type default))
          (fill (type background))
        )
        (polyline
          (pts
            (xy 5.08 -5.08)
            (xy 3.81 -5.715)
            (xy 3.81 -4.445)
            (xy 5.08 -5.08)
          )
          (stroke (width 0.254) (type default))
          (fill (type background))
        )
        (polyline
          (pts
            (xy 5.08 -5.08)
            (xy 6.35 -4.445)
            (xy 6.35 -5.715)
            (xy 5.08 -5.08)
          )
          (stroke (width 0.254) (type default))
          (fill (type background))
        )
        (polyline
          (pts
            (xy 5.08 -2.54)
            (xy 3.81 -3.175)
            (xy 3.81 -1.905)
            (xy 5.08 -2.54)
          )
          (stroke (width 0.254) (type default))
          (fill (type background))
        )
        (polyline
          (pts
            (xy 5.08 -2.54)
            (xy 6.35 -3.175)
            (xy 6.35 -1.905)
            (xy 5.08 -2.54)
          )
          (stroke (width 0.254) (type default))
          (fill (type background))
        )
        (polyline
          (pts
            (xy 5.08 0)
            (xy 3.81 -0.635)
            (xy 3.81 0.635)
            (xy 5.08 0)
          )
          (stroke (width 0.254) (type default))
          (fill (type background))
        )
        (polyline
          (pts
            (xy 5.08 0)
            (xy 6.35 -0.635)
            (xy 6.35 0.635)
            (xy 5.08 0)
          )
          (stroke (width 0.254) (type default))
          (fill (type background))
        )
        (polyline
          (pts
            (xy 6.35 -12.065)
            (xy 6.35 -13.335)
            (xy 5.08 -12.7)
            (xy 6.35 -12.065)
          )
          (stroke (width 0.254) (type default))
          (fill (type background))
        )
        (polyline
          (pts
            (xy 6.35 -6.985)
            (xy 6.35 -8.255)
            (xy 5.08 -7.62)
            (xy 6.35 -6.985)
          )
          (stroke (width 0.254) (type default))
          (fill (type background))
        )
        (rectangle (start 2.54 2.54) (end 8.89 -17.78)
          (stroke (width 0.254) (type default))
          (fill (type background))
        )
        (circle (center 7.62 -12.7) (radius 0.254)
          (stroke (width 0.254) (type default))
          (fill (type background))
        )
        (circle (center 7.62 -10.16) (radius 0.254)
          (stroke (width 0.254) (type default))
          (fill (type background))
        )
        (circle (center 7.62 -10.16) (radius 0.254)
          (stroke (width 0.254) (type default))
          (fill (type background))
        )
        (circle (center 7.62 -7.62) (radius 0.254)
          (stroke (width 0.254) (type default))
          (fill (type background))
        )
        (circle (center 7.62 -5.08) (radius 0.254)
          (stroke (width 0.254) (type default))
          (fill (type background))
        )
        (circle (center 7.62 -5.08) (radius 0.254)
          (stroke (width 0.254) (type default))
          (fill (type background))
        )
        (circle (center 7.62 -2.54) (radius 0.254)
          (stroke (width 0.254) (type default))
          (fill (type background))
        )
        (pin passive line (at 0 -12.7 0) (length 2.54) hide
          (name "~" (effects (font (size 1.27 1.27))))
          (number "1" (effects (font (size 1.27 1.27))))
        )
        (pin passive line (at 0 -15.24 0) (length 2.54)
          (name "~" (effects (font (size 1.27 1.27))))
          (number "10" (effects (font (size 1.27 1.27))))
        )
        (pin passive line (at 0 -10.16 0) (length 2.54) hide
          (name "~" (effects (font (size 1.27 1.27))))
          (number "2" (effects (font (size 1.27 1.27))))
        )
        (pin passive line (at 0 -7.62 0) (length 2.54) hide
          (name "~" (effects (font (size 1.27 1.27))))
          (number "3" (effects (font (size 1.27 1.27))))
        )
        (pin passive line (at 0 -5.08 0) (length 2.54) hide
          (name "~" (effects (font (size 1.27 1.27))))
          (number "4" (effects (font (size 1.27 1.27))))
        )
        (pin passive line (at 0 -15.24 0) (length 2.54) hide
          (name "~" (effects (font (size 1.27 1.27))))
          (number "5" (effects (font (size 1.27 1.27))))
        )
        (pin passive line (at 0 -2.54 0) (length 2.54) hide
          (name "~" (effects (font (size 1.27 1.27))))
          (number "6" (effects (font (size 1.27 1.27))))
        )
        (pin passive line (at 0 0 0) (length 2.54) hide
          (name "~" (effects (font (size 1.27 1.27))))
          (number "7" (effects (font (size 1.27 1.27))))
        )
        (pin passive line (at 0 0 0) (length 2.54)
          (name "~" (effects (font (size 1.27 1.27))))
          (number "8" (effects (font (size 1.27 1.27))))
        )
        (pin passive line (at 0 -2.54 0) (length 2.54)
          (name "~" (effects (font (size 1.27 1.27))))
          (number "9" (effects (font (size 1.27 1.27))))
        )
      )
    )
	(symbol "antmicroTestPoints:TP_1206_SMD_RCW-0C" (pin_names hide) (in_bom yes) (on_board yes)
      (property "Reference" "TP" (at 17.78 -5.08 0)
        (effects (font (size 1.27 1.27) (thickness 0.15)) (justify left bottom))
      )
      (property "Value" "TP_1206_SMD_RCW-0C" (at 17.78 -7.62 0)
        (effects (font (size 1.27 1.27) (thickness 0.15)) (justify left bottom))
      )
      (property "Footprint" "antmicro-footprints:TP_1206_SMD_RCW-0C" (at 17.78 -10.16 0)
        (effects (font (size 1.27 1.27) (thickness 0.15)) (justify left bottom) hide)
      )
      (property "Datasheet" "https://www.te.com/commerce/DocumentDelivery/DDEController?Action=srchrtrv&DocNm=1773266&DocType=DS&DocLang=English" (at 17.78 -12.7 0)
        (effects (font (size 1.27 1.27) (thickness 0.15)) (justify left bottom) hide)
      )
      (property "MPN" "RCW-0C" (at 17.78 -15.24 0)
        (effects (font (size 1.27 1.27) (thickness 0.15)) (justify left bottom) hide)
      )
      (property "Manufacturer" "TE Connectivity" (at 17.78 -17.78 0)
        (effects (font (size 1.27 1.27) (thickness 0.15)) (justify left bottom) hide)
      )
      (property "Author" "Antmicro" (at 17.78 -20.32 0)
        (effects (font (size 1.27 1.27) (thickness 0.15)) (justify left bottom) hide)
      )
      (property "License" "Apache-2.0" (at 17.78 -22.86 0)
        (effects (font (size 1.27 1.27) (thickness 0.15)) (justify left bottom) hide)
      )
      (property "ki_keywords" "1206, SMT, TESTPOINT, PASSIVE" (at 0 0 0)
        (effects (font (size 1.27 1.27)) hide)
      )
      (property "ki_description" "Circuit Probe Pad, SMD, Test Point, 1206" (at 0 0 0)
        (effects (font (size 1.27 1.27)) hide)
      )
      (symbol "TP_1206_SMD_RCW-0C_1_1"
        (circle (center 3.175 0) (radius 0.635)
          (stroke (width 0.254) (type default))
          (fill (type none))
        )
        (pin passive line (at 0 0 0) (length 2.54)
          (name "1" (effects (font (size 1.27 1.27))))
          (number "1" (effects (font (size 1.27 1.27))))
        )
      )
    )
	(symbol "antmicroTestPoints:TP_1mm_SMD" (pin_names hide) (in_bom no) (on_board yes)
      (property "Reference" "TP" (at 15.24 -5.08 0)
        (effects (font (size 1.27 1.27) (thickness 0.15)) (justify left bottom))
      )
      (property "Value" "TP_1mm_SMD" (at 15.24 -7.62 0)
        (effects (font (size 1.27 1.27) (thickness 0.15)) (justify left bottom) hide)
      )
      (property "Footprint" "antmicro-footprints:TP_SMD_1mm" (at 15.24 -10.16 0)
        (effects (font (size 1.27 1.27) (thickness 0.15)) (justify left bottom) hide)
      )
      (property "Datasheet" "" (at 17.78 -12.7 0)
        (effects (font (size 1.27 1.27) (thickness 0.15)) (justify left bottom) hide)
      )
      (property "MPN" "" (at 0 0 0)
        (effects (font (size 1.27 1.27)) hide)
      )
      (property "Manufacturer" "" (at 0 0 0)
        (effects (font (size 1.27 1.27)) hide)
      )
      (property "Author" "Antmicro" (at 15.24 -15.24 0)
        (effects (font (size 1.27 1.27) (thickness 0.15)) (justify left bottom) hide)
      )
      (property "License" "Apache-2.0" (at 15.24 -17.78 0)
        (effects (font (size 1.27 1.27) (thickness 0.15)) (justify left bottom) hide)
      )
      (property "ki_keywords" "TESTPOINT" (at 0 0 0)
        (effects (font (size 1.27 1.27)) hide)
      )
      (property "ki_description" "Test point 1mm SMD" (at 0 0 0)
        (effects (font (size 1.27 1.27)) hide)
      )
      (symbol "TP_1mm_SMD_1_1"
        (circle (center 3.175 0) (radius 0.635)
          (stroke (width 0.254) (type default))
          (fill (type none))
        )
        (pin passive line (at 0 0 0) (length 2.54)
          (name "1" (effects (font (size 1.27 1.27))))
          (number "1" (effects (font (size 1.27 1.27))))
        )
      )
    )
	(symbol "antmicroTransistorsFETsMOSFETsSingle:2N7002_SOT-23-3" (pin_names (offset 0)) (in_bom yes) (on_board yes)
      (property "Reference" "Q" (at 22.86 -5.08 0)
        (effects (font (size 1.27 1.27) (thickness 0.15)) (justify left bottom))
      )
      (property "Value" "2N7002_SOT-23-3" (at 22.86 -7.62 0)
        (effects (font (size 1.27 1.27) (thickness 0.15)) (justify left bottom) hide)
      )
      (property "Footprint" "antmicro-footprints:SOT-23-3" (at 22.86 -10.16 0)
        (effects (font (size 1.27 1.27) (thickness 0.15)) (justify left bottom) hide)
      )
      (property "Datasheet" "https://www.onsemi.com/pub/Collateral/NDS7002A-D.PDF" (at 22.86 -12.7 0)
        (effects (font (size 1.27 1.27) (thickness 0.15)) (justify left bottom) hide)
      )
      (property "MPN" "2N7002" (at 22.86 -15.24 0)
        (effects (font (size 1.27 1.27) (thickness 0.15)) (justify left bottom))
      )
      (property "Manufacturer" "ON Semiconductor" (at 22.86 -17.78 0)
        (effects (font (size 1.27 1.27) (thickness 0.15)) (justify left bottom) hide)
      )
      (property "Author" "Antmicro" (at 22.86 -20.32 0)
        (effects (font (size 1.27 1.27) (thickness 0.15)) (justify left bottom) hide)
      )
      (property "License" "Apache-2.0" (at 22.86 -22.86 0)
        (effects (font (size 1.27 1.27) (thickness 0.15)) (justify left bottom) hide)
      )
      (property "ki_keywords" "SMT, TRANSISTOR, SEMICONDUCTOR, NMOS" (at 0 0 0)
        (effects (font (size 1.27 1.27)) hide)
      )
      (property "ki_description" "Power MOSFET, N Channel, 60 V, 115 mA, 1.2 ohm, SOT-23, Surface Mount" (at 0 0 0)
        (effects (font (size 1.27 1.27)) hide)
      )
      (symbol "2N7002_SOT-23-3_1_1"
        (polyline
          (pts
            (xy 5.08 1.143)
            (xy 5.08 0.635)
          )
          (stroke (width 0.254) (type default))
          (fill (type background))
        )
        (polyline
          (pts
            (xy 5.08 1.143)
            (xy 5.08 1.651)
          )
          (stroke (width 0.254) (type default))
          (fill (type background))
        )
        (polyline
          (pts
            (xy 5.08 2.54)
            (xy 5.08 2.032)
          )
          (stroke (width 0.254) (type default))
          (fill (type background))
        )
        (polyline
          (pts
            (xy 5.08 2.54)
            (xy 5.08 3.048)
          )
          (stroke (width 0.254) (type default))
          (fill (type background))
        )
        (polyline
          (pts
            (xy 5.08 4.445)
            (xy 5.08 3.429)
          )
          (stroke (width 0.254) (type default))
          (fill (type background))
        )
        (polyline
          (pts
            (xy 7.62 1.143)
            (xy 5.08 1.143)
          )
          (stroke (width 0.254) (type default))
          (fill (type background))
        )
        (polyline
          (pts
            (xy 9.144 3.048)
            (xy 8.128 3.048)
          )
          (stroke (width 0.254) (type default))
          (fill (type background))
        )
        (polyline
          (pts
            (xy 2.54 0)
            (xy 4.572 0)
            (xy 4.572 3.937)
          )
          (stroke (width 0.254) (type default))
          (fill (type none))
        )
        (polyline
          (pts
            (xy 7.62 -1.27)
            (xy 7.62 2.54)
            (xy 5.08 2.54)
          )
          (stroke (width 0.254) (type default))
          (fill (type none))
        )
        (polyline
          (pts
            (xy 7.62 6.35)
            (xy 7.62 3.937)
            (xy 5.08 3.937)
          )
          (stroke (width 0.254) (type default))
          (fill (type none))
        )
        (polyline
          (pts
            (xy 5.08 2.54)
            (xy 5.842 3.048)
            (xy 5.842 2.032)
            (xy 5.08 2.54)
          )
          (stroke (width 0.254) (type default))
          (fill (type outline))
        )
        (polyline
          (pts
            (xy 8.636 3.048)
            (xy 8.128 2.286)
            (xy 9.144 2.286)
            (xy 8.636 3.048)
          )
          (stroke (width 0.254) (type default))
          (fill (type outline))
        )
        (polyline
          (pts
            (xy 7.493 0.635)
            (xy 8.636 0.635)
            (xy 8.636 3.937)
            (xy 8.636 4.445)
            (xy 7.493 4.445)
          )
          (stroke (width 0.254) (type default))
          (fill (type background))
        )
        (circle (center 6.35 2.54) (radius 3.302)
          (stroke (width 0.254) (type default))
          (fill (type background))
        )
        (circle (center 7.62 0.635) (radius 0.127)
          (stroke (width 0.254) (type default))
          (fill (type background))
        )
        (circle (center 7.62 1.143) (radius 0.127)
          (stroke (width 0.254) (type default))
          (fill (type background))
        )
        (circle (center 7.62 4.445) (radius 0.127)
          (stroke (width 0.254) (type default))
          (fill (type background))
        )
        (pin passive line (at 0 0 0) (length 2.54)
          (name "G" (effects (font (size 1.27 1.27))))
          (number "1" (effects (font (size 1.27 1.27))))
        )
        (pin passive line (at 7.62 -3.81 90) (length 2.54)
          (name "S" (effects (font (size 1.27 1.27))))
          (number "2" (effects (font (size 1.27 1.27))))
        )
        (pin passive line (at 7.62 8.89 270) (length 2.54)
          (name "D" (effects (font (size 1.27 1.27))))
          (number "3" (effects (font (size 1.27 1.27))))
        )
      )
    )
	(symbol "antmicroUSBConnectors:USB-Micro-B_Amphenol_10118192-0001LF" (in_bom yes) (on_board yes)
      (property "Reference" "J" (at 33.02 -2.54 0)
        (effects (font (size 1.27 1.27) (thickness 0.15)) (justify left bottom))
      )
      (property "Value" "USB-Micro-B_Amphenol_10118192-0001LF" (at 33.02 -5.08 0)
        (effects (font (size 1.27 1.27) (thickness 0.15)) (justify left bottom))
      )
      (property "Footprint" "antmicro-footprints:USB-Micro-B_Receptacle_Amphenol_10118192" (at 33.02 -7.62 0)
        (effects (font (size 1.27 1.27) (thickness 0.15)) (justify left bottom) hide)
      )
      (property "Datasheet" "http://www.amphenol-icc.com/media/wysiwyg/files/drawing/10118192.pdf" (at 33.02 -10.16 0)
        (effects (font (size 1.27 1.27) (thickness 0.15)) (justify left bottom) hide)
      )
      (property "MPN" "10118192-0001LF" (at 33.02 -12.7 0)
        (effects (font (size 1.27 1.27) (thickness 0.15)) (justify left bottom) hide)
      )
      (property "Manufacturer" "Amphenol" (at 33.02 -15.24 0)
        (effects (font (size 1.27 1.27) (thickness 0.15)) (justify left bottom) hide)
      )
      (property "Author" "Antmicro" (at 33.02 -20.32 0)
        (effects (font (size 1.27 1.27) (thickness 0.15)) (justify left bottom) hide)
      )
      (property "License" "Apache-2.0" (at 33.02 -22.86 0)
        (effects (font (size 1.27 1.27) (thickness 0.15)) (justify left bottom) hide)
      )
      (property "ki_keywords" "USB, MICRO, CONNECTOR, SMT, HORIZONTAL" (at 0 0 0)
        (effects (font (size 1.27 1.27)) hide)
      )
      (property "ki_description" "USB - micro B USB 2.0 Receptacle Connector 5 Position Surface Mount, Right Angle" (at 0 0 0)
        (effects (font (size 1.27 1.27)) hide)
      )
      (symbol "USB-Micro-B_Amphenol_10118192-0001LF_0_1"
        (rectangle (start -13.335 -7.366) (end -13.97 -12.446)
          (stroke (width 0.127) (type default))
          (fill (type outline))
        )
        (polyline
          (pts
            (xy -13.97 -13.97)
            (xy -15.24 -12.7)
          )
          (stroke (width 0.254) (type default))
          (fill (type none))
        )
        (polyline
          (pts
            (xy -12.7 -13.97)
            (xy -13.97 -13.97)
          )
          (stroke (width 0.254) (type default))
          (fill (type none))
        )
        (polyline
          (pts
            (xy -12.7 -13.97)
            (xy -12.7 -5.715)
          )
          (stroke (width 0.254) (type default))
          (fill (type none))
        )
        (polyline
          (pts
            (xy -12.7 -5.715)
            (xy -13.97 -5.715)
          )
          (stroke (width 0.254) (type default))
          (fill (type none))
        )
        (polyline
          (pts
            (xy -13.97 -5.715)
            (xy -15.24 -6.985)
            (xy -15.24 -12.7)
          )
          (stroke (width 0.254) (type default))
          (fill (type none))
        )
      )
      (symbol "USB-Micro-B_Amphenol_10118192-0001LF_1_1"
        (rectangle (start -21.59 2.54) (end -2.54 -22.86)
          (stroke (width 0.254) (type default))
          (fill (type background))
        )
        (circle (center -18.796 -10.414) (radius 0.284)
          (stroke (width 0.254) (type default))
          (fill (type outline))
        )
        (circle (center -17.907 -13.208) (radius 0.5236)
          (stroke (width 0.254) (type default))
          (fill (type outline))
        )
        (rectangle (start -17.399 -10.414) (end -16.637 -9.652)
          (stroke (width 0.254) (type default))
          (fill (type outline))
        )
        (polyline
          (pts
            (xy -17.907 -13.081)
            (xy -17.907 -8.763)
          )
          (stroke (width 0.254) (type default))
          (fill (type background))
        )
        (polyline
          (pts
            (xy -17.907 -12.319)
            (xy -18.796 -11.43)
            (xy -18.796 -10.795)
          )
          (stroke (width 0.254) (type default))
          (fill (type background))
        )
        (polyline
          (pts
            (xy -17.907 -11.938)
            (xy -17.018 -11.049)
            (xy -17.018 -10.414)
          )
          (stroke (width 0.254) (type default))
          (fill (type background))
        )
        (polyline
          (pts
            (xy -18.542 -8.763)
            (xy -17.907 -7.62)
            (xy -17.272 -8.763)
            (xy -18.542 -8.763)
          )
          (stroke (width 0.254) (type default))
          (fill (type outline))
        )
        (pin passive line (at 0 0 180) (length 2.54)
          (name "VBUS" (effects (font (size 1.27 1.27))))
          (number "1" (effects (font (size 1.27 1.27))))
        )
        (pin bidirectional line (at 0 -7.62 180) (length 2.54)
          (name "D-" (effects (font (size 1.27 1.27))))
          (number "2" (effects (font (size 1.27 1.27))))
        )
        (pin bidirectional line (at 0 -5.08 180) (length 2.54)
          (name "D+" (effects (font (size 1.27 1.27))))
          (number "3" (effects (font (size 1.27 1.27))))
        )
        (pin bidirectional line (at 0 -12.7 180) (length 2.54)
          (name "ID" (effects (font (size 1.27 1.27))))
          (number "4" (effects (font (size 1.27 1.27))))
        )
        (pin power_in line (at 0 -17.78 180) (length 2.54)
          (name "GND" (effects (font (size 1.27 1.27))))
          (number "5" (effects (font (size 1.27 1.27))))
        )
        (pin passive line (at 0 -20.32 180) (length 2.54)
          (name "SHIELD" (effects (font (size 1.27 1.27))))
          (number "SH" (effects (font (size 1.27 1.27))))
        )
      )
    )
	(symbol "antmicroWire2BoardConnectors:Molex_Pico-Lock_1x2_504050-0291" (pin_names hide) (in_bom yes) (on_board yes)
      (property "Reference" "J" (at 8.89 0 0)
        (effects (font (size 1.27 1.27) (thickness 0.15)) (justify left bottom))
      )
      (property "Value" "Molex_Pico-Lock_1x2_504050-0291" (at 8.89 -2.54 0)
        (effects (font (size 1.27 1.27) (thickness 0.15)) (justify left bottom) hide)
      )
      (property "Footprint" "antmicro-footprints:Conn_Molex_Pico-Lock_1x2_504050-0291" (at 8.89 -5.08 0)
        (effects (font (size 1.27 1.27) (thickness 0.15)) (justify left bottom) hide)
      )
      (property "Datasheet" "https://tools.molex.com/pdm_docs/ps/PS-504051-001-001.pdf" (at 8.89 -7.62 0)
        (effects (font (size 1.27 1.27) (thickness 0.15)) (justify left bottom) hide)
      )
      (property "Manufacturer" "Molex" (at 8.89 -10.16 0)
        (effects (font (size 1.27 1.27) (thickness 0.15)) (justify left bottom) hide)
      )
      (property "MPN" "504050-0291" (at 8.89 -12.7 0)
        (effects (font (size 1.27 1.27) (thickness 0.15)) (justify left bottom))
      )
      (property "Author" "Antmicro" (at 8.89 -15.24 0)
        (effects (font (size 1.27 1.27) (thickness 0.15)) (justify left bottom) hide)
      )
      (property "License" "Apache-2.0" (at 8.89 -17.78 0)
        (effects (font (size 1.27 1.27) (thickness 0.15)) (justify left bottom) hide)
      )
      (property "ki_keywords" "CONNECTOR, HEADER, SMT" (at 0 0 0)
        (effects (font (size 1.27 1.27)) hide)
      )
      (property "ki_description" "Connector Header Surface Mount, Right Angle 2 position 0.059\" (1.50mm)" (at 0 0 0)
        (effects (font (size 1.27 1.27)) hide)
      )
      (symbol "Molex_Pico-Lock_1x2_504050-0291_1_1"
        (rectangle (start 2.54 -4.953) (end 3.81 -5.207)
          (stroke (width 0.254) (type default))
          (fill (type background))
        )
        (rectangle (start 2.54 -2.413) (end 3.81 -2.667)
          (stroke (width 0.254) (type default))
          (fill (type background))
        )
        (rectangle (start 2.54 0.127) (end 3.81 -0.127)
          (stroke (width 0.254) (type default))
          (fill (type background))
        )
        (rectangle (start 2.54 1.27) (end 5.08 -6.35)
          (stroke (width 0.254) (type default))
          (fill (type background))
        )
        (pin passive line (at 0 0 0) (length 2.54)
          (name "1" (effects (font (size 1.27 1.27))))
          (number "1" (effects (font (size 1.27 1.27))))
        )
        (pin passive line (at 0 -2.54 0) (length 2.54)
          (name "2" (effects (font (size 1.27 1.27))))
          (number "2" (effects (font (size 1.27 1.27))))
        )
        (pin passive line (at 0 -5.08 0) (length 2.54)
          (name "SH" (effects (font (size 1.27 1.27))))
          (number "SH" (effects (font (size 1.27 1.27))))
        )
        (pin passive line (at 0 -5.08 0) (length 2.54) hide
          (name "SH" (effects (font (size 1.27 1.27))))
          (number "SH" (effects (font (size 1.27 1.27))))
        )
      )
    )
	(symbol "antmicropower:GND" (power) (pin_numbers hide) (pin_names hide) (in_bom yes) (on_board yes)
      (property "Reference" "#PWR" (at 8.89 -2.54 0)
        (effects (font (size 1.27 1.27) (thickness 0.15)) (justify left bottom) hide)
      )
      (property "Value" "GND" (at 8.89 -5.08 0)
        (effects (font (size 1.27 1.27) (thickness 0.15)) (justify left bottom))
      )
      (property "Footprint" "" (at 8.89 -7.62 0)
        (effects (font (size 1.27 1.27) (thickness 0.15)) (justify left bottom) hide)
      )
      (property "Datasheet" "" (at 8.89 -12.7 0)
        (effects (font (size 1.27 1.27) (thickness 0.15)) (justify left bottom) hide)
      )
      (property "Author" "Antmicro" (at 8.89 -7.62 0)
        (effects (font (size 1.27 1.27) (thickness 0.15)) (justify left bottom) hide)
      )
      (property "License" "Apache-2.0" (at 8.89 -10.16 0)
        (effects (font (size 1.27 1.27) (thickness 0.15)) (justify left bottom) hide)
      )
      (symbol "GND_1_1"
        (polyline
          (pts
            (xy 0 0)
            (xy 0 -1.27)
            (xy 1.27 -1.27)
            (xy 0 -2.54)
            (xy -1.27 -1.27)
            (xy 0 -1.27)
          )
          (stroke (width 0) (type default))
          (fill (type none))
        )
        (pin power_in line (at 0 0 270) (length 0)
          (name "GND" (effects (font (size 1.27 1.27))))
          (number "1" (effects (font (size 1.27 1.27))))
        )
      )
    )
	(symbol "antmicropower:PWR_FLAG" (power) (pin_numbers hide) (pin_names (offset 0) hide) (in_bom yes) (on_board yes)
      (property "Reference" "#FLG" (at 0 1.905 0)
        (effects (font (size 1.27 1.27)) hide)
      )
      (property "Value" "PWR_FLAG" (at 0 3.81 0)
        (effects (font (size 1.27 1.27)))
      )
      (property "Footprint" "" (at 0 0 0)
        (effects (font (size 1.27 1.27)) hide)
      )
      (property "Datasheet" "" (at 0 0 0)
        (effects (font (size 1.27 1.27)) hide)
      )
      (symbol "PWR_FLAG_0_0"
        (pin power_out line (at 0 0 90) (length 0)
          (name "pwr" (effects (font (size 1.27 1.27))))
          (number "1" (effects (font (size 1.27 1.27))))
        )
      )
      (symbol "PWR_FLAG_0_1"
        (polyline
          (pts
            (xy 0 0)
            (xy 0 1.27)
            (xy -1.016 1.905)
            (xy 0 2.54)
            (xy 1.016 1.905)
            (xy 0 1.27)
          )
          (stroke (width 0) (type default))
          (fill (type none))
        )
      )
    )
)
